FILE_TYPE = MACRO_DRAWING;
SET COLOR_WIRE YELLOW;
SET COLOR_PROP ORANGE;
SET COLOR_DOT WHITE;
SET COLOR_ARC YELLOW;
SET COLOR_BODY GREEN;
SET COLOR_NOTE PURPLE;
SET PROP_DISPLAY VALUE;
SET PAGE_NUMBER P190;
FORCEADD OFFPAGE..1
(-8075 1875);
FORCEPROP 2 LAST $XR4 215 
J 0
(-8807 1875);
DISPLAY 0.638298 (-8807 1875);
PAINT MONO (-8807 1875);
FORCEPROP 2 LAST $XR3 213 
J 0
(-8687 1875);
DISPLAY 0.638298 (-8687 1875);
PAINT MONO (-8687 1875);
FORCEPROP 2 LAST $XR2 212 
J 0
(-8567 1875);
DISPLAY 0.638298 (-8567 1875);
PAINT MONO (-8567 1875);
FORCEPROP 2 LAST $XR1 211 
J 0
(-8447 1875);
DISPLAY 0.638298 (-8447 1875);
PAINT MONO (-8447 1875);
FORCEPROP 2 LAST $XR0 210 
J 0
(-8327 1875);
DISPLAY 0.638298 (-8327 1875);
PAINT MONO (-8327 1875);
FORCEPROP 2 LAST $XR5 216 
J 0
(-8927 1875);
DISPLAY 0.638298 (-8927 1875);
PAINT MONO (-8927 1875);
FORCEPROP 2 LAST CDS_LIB standard
J 0
(-8075 1875);
DISPLAY INVISIBLE (-8075 1875);
FORCEPROP 1 LAST OFFPAGE TRUE
J 0
(-7750 1750);
DISPLAY 0.872340 (-7750 1750);
PAINT GREEN (-7750 1750);
DISPLAY INVISIBLE (-7750 1750);
FORCEPROP 1 LAST COMMENT_BODY TRUE
J 0
(-7950 1775);
DISPLAY 0.872340 (-7950 1775);
PAINT GREEN (-7950 1775);
DISPLAY INVISIBLE (-7950 1775);
FORCEPROP 2 LAST PATH I1
J 0
(-8325 1925);
DISPLAY 0.680851 (-8325 1925);
DISPLAY INVISIBLE (-8325 1925);
FORCEADD UNIVERSAL_GND..1
(-7525 2125);
FORCEPROP 3 LASTPIN (-7525 2175) SIG_NAME GND\g
J 0
(-7515 2185);
DISPLAY 0.659574 (-7515 2185);
PAINT MONO (-7515 2185);
DISPLAY INVISIBLE (-7515 2185);
FORCEPROP 2 LAST CDS_LIB pure_quanta_power
J 0
(-7525 2125);
DISPLAY INVISIBLE (-7525 2125);
FORCEPROP 1 LAST HDL_POWER GND
J 1
(-7500 2050);
DISPLAY 0.872340 (-7500 2050);
PAINT GREEN (-7500 2050);
DISPLAY INVISIBLE (-7500 2050);
FORCEPROP 1 LAST PATH I10
J 0
(-7450 2125);
DISPLAY 0.872340 (-7450 2125);
PAINT AQUA (-7450 2125);
DISPLAY INVISIBLE (-7450 2125);
FORCEADD Q_CAP..1
(-7525 2325);
FORCEPROP 1 LAST LOCATION PC320
J 0
(-7475 2425);
DISPLAY 0.489362 (-7475 2425);
PAINT SKYBLUE (-7475 2425);
FORCEPROP 0 LAST $SEC 1
J 0
(-7475 2475);
DISPLAY 0.680851 (-7475 2475);
PAINT MONO (-7475 2475);
DISPLAY INVISIBLE (-7475 2475);
FORCEPROP 0 LAST CDS_SEC 1
J 0
(-7475 2475);
DISPLAY 1.021277 (-7475 2475);
DISPLAY INVISIBLE (-7475 2475);
FORCEPROP 1 LASTPIN (-7525 2425) $PN 1
J 0
(-7515 2405);
DISPLAY 0.489362 (-7515 2405);
PAINT MONO (-7515 2405);
FORCEPROP 1 LASTPIN (-7525 2225) $PN 2
J 0
(-7515 2205);
DISPLAY 0.489362 (-7515 2205);
PAINT MONO (-7515 2205);
FORCEPROP 1 LAST VALUE 2.2UF
J 0
(-7475 2375);
DISPLAY 0.489362 (-7475 2375);
PAINT SKYBLUE (-7475 2375);
FORCEPROP 1 LAST PACK_TYPE C0402
J 0
(-7475 2125);
DISPLAY 0.489362 (-7475 2125);
PAINT SKYBLUE (-7475 2125);
FORCEPROP 1 LAST VOLTAGE 10V
J 0
(-7475 2325);
DISPLAY 0.489362 (-7475 2325);
PAINT SKYBLUE (-7475 2325);
FORCEPROP 1 LAST TOLERANCE 10%
J 0
(-7475 2275);
DISPLAY 0.489362 (-7475 2275);
PAINT SKYBLUE (-7475 2275);
FORCEPROP 1 LAST MATERIAL X6S
J 0
(-7475 2225);
DISPLAY 0.489362 (-7475 2225);
PAINT SKYBLUE (-7475 2225);
FORCEPROP 2 LAST CDS_LIB pure_quanta
J 0
(-7525 2325);
DISPLAY INVISIBLE (-7525 2325);
FORCEPROP 1 LAST PATH I11
J 0
(-7475 2475);
DISPLAY 0.978723 (-7475 2475);
PAINT WHITE (-7475 2475);
DISPLAY INVISIBLE (-7475 2475);
FORCEPROP 1 LAST PART_NUMBER CH5222KEB01
J 0
(-7475 2175);
DISPLAY 0.489362 (-7475 2175);
PAINT SKYBLUE (-7475 2175);
DISPLAY INVISIBLE (-7475 2175);
FORCEADD Q_RES..2
(-7525 2875);
FORCEPROP 1 LAST LOCATION PR206
J 0
(-7480 3000);
DISPLAY 0.489362 (-7480 3000);
PAINT SKYBLUE (-7480 3000);
FORCEPROP 0 LAST $SEC 1
J 0
(-7475 3050);
DISPLAY 0.680851 (-7475 3050);
PAINT MONO (-7475 3050);
DISPLAY INVISIBLE (-7475 3050);
FORCEPROP 0 LAST CDS_SEC 1
J 0
(-7475 3050);
DISPLAY 1.021277 (-7475 3050);
DISPLAY INVISIBLE (-7475 3050);
FORCEPROP 1 LASTPIN (-7525 2975) $PN 1
J 0
(-7520 2937);
DISPLAY 0.489362 (-7520 2937);
PAINT MONO (-7520 2937);
FORCEPROP 1 LASTPIN (-7525 2775) $PN 2
J 0
(-7520 2785);
DISPLAY 0.489362 (-7520 2785);
PAINT MONO (-7520 2785);
FORCEPROP 1 LAST PACK_TYPE 0402LF
J 0
(-7475 2700);
DISPLAY 0.489362 (-7475 2700);
PAINT SKYBLUE (-7475 2700);
FORCEPROP 1 LAST WATTAGE 1/16W
J 0
(-7475 2850);
DISPLAY 0.489362 (-7475 2850);
PAINT SKYBLUE (-7475 2850);
FORCEPROP 1 LAST MATERIAL CHIP
J 0
(-7475 2800);
DISPLAY 0.489362 (-7475 2800);
PAINT SKYBLUE (-7475 2800);
FORCEPROP 1 LAST TOLERANCE 1%
J 0
(-7475 2900);
DISPLAY 0.489362 (-7475 2900);
PAINT SKYBLUE (-7475 2900);
FORCEPROP 1 LAST VALUE 2.2
J 0
(-7475 2950);
DISPLAY 0.489362 (-7475 2950);
PAINT SKYBLUE (-7475 2950);
FORCEPROP 2 LAST CDS_LIB pure_quanta
J 0
(-7525 2875);
DISPLAY INVISIBLE (-7525 2875);
FORCEPROP 1 LAST PATH I12
J 0
(-7475 3050);
DISPLAY 0.978723 (-7475 3050);
PAINT WHITE (-7475 3050);
DISPLAY INVISIBLE (-7475 3050);
FORCEPROP 1 LAST PART_NUMBER CS-2202FB01
J 0
(-7475 2750);
DISPLAY 0.489362 (-7475 2750);
PAINT SKYBLUE (-7475 2750);
DISPLAY INVISIBLE (-7475 2750);
FORCEADD VCC_CORE..1
(-7525 3275);
FORCEPROP 3 LASTPIN (-7525 3225) SIG_NAME PVDDCR_CPU0_P1_PVCC\g
J 0
(-7515 3235);
DISPLAY 0.659574 (-7515 3235);
PAINT MONO (-7515 3235);
DISPLAY INVISIBLE (-7515 3235);
FORCEPROP 1 LAST HDL_POWER PVDDCR_CPU0_P1_PVCC
J 1
(-7525 3325);
DISPLAY 0.489362 (-7525 3325);
PAINT GREEN (-7525 3325);
FORCEPROP 2 LAST CDS_LIB pure_quanta_power
J 0
(-7525 3275);
DISPLAY INVISIBLE (-7525 3275);
FORCEPROP 1 LAST PATH I13
J 0
(-7475 3300);
DISPLAY 0.872340 (-7475 3300);
PAINT AQUA (-7475 3300);
DISPLAY INVISIBLE (-7475 3300);
FORCEADD Q_CAP..1
(-7175 2900);
FORCEPROP 1 LAST LOCATION PC322_SOP1_2
J 0
(-7125 3000);
DISPLAY 0.489362 (-7125 3000);
PAINT SKYBLUE (-7125 3000);
FORCEPROP 0 LAST $SEC 1
J 0
(-7125 3050);
DISPLAY 0.680851 (-7125 3050);
PAINT MONO (-7125 3050);
DISPLAY INVISIBLE (-7125 3050);
FORCEPROP 0 LAST CDS_SEC 1
J 0
(-7125 3050);
DISPLAY 1.021277 (-7125 3050);
DISPLAY INVISIBLE (-7125 3050);
FORCEPROP 1 LASTPIN (-7175 3000) $PN 1
J 0
(-7165 2980);
DISPLAY 0.489362 (-7165 2980);
PAINT MONO (-7165 2980);
FORCEPROP 1 LASTPIN (-7175 2800) $PN 2
J 0
(-7165 2780);
DISPLAY 0.489362 (-7165 2780);
PAINT MONO (-7165 2780);
FORCEPROP 1 LAST PACK_TYPE C0402
J 0
(-7125 2700);
DISPLAY 0.489362 (-7125 2700);
PAINT SKYBLUE (-7125 2700);
FORCEPROP 1 LAST VOLTAGE 10V
J 0
(-7125 2900);
DISPLAY 0.489362 (-7125 2900);
PAINT SKYBLUE (-7125 2900);
FORCEPROP 1 LAST VALUE 2.2UF
J 0
(-7125 2950);
DISPLAY 0.489362 (-7125 2950);
PAINT SKYBLUE (-7125 2950);
FORCEPROP 1 LAST TOLERANCE 10%
J 0
(-7125 2850);
DISPLAY 0.489362 (-7125 2850);
PAINT SKYBLUE (-7125 2850);
FORCEPROP 1 LAST MATERIAL X6S
J 0
(-7125 2800);
DISPLAY 0.489362 (-7125 2800);
PAINT SKYBLUE (-7125 2800);
FORCEPROP 2 LAST CDS_LIB pure_quanta
J 0
(-7175 2900);
DISPLAY INVISIBLE (-7175 2900);
FORCEPROP 1 LAST PATH I14
J 0
(-7125 3050);
DISPLAY 0.978723 (-7125 3050);
PAINT WHITE (-7125 3050);
DISPLAY INVISIBLE (-7125 3050);
FORCEPROP 1 LAST PART_NUMBER CH5222KEB01
J 0
(-7125 2750);
DISPLAY 0.489362 (-7125 2750);
PAINT SKYBLUE (-7125 2750);
DISPLAY INVISIBLE (-7125 2750);
FORCEADD UNIVERSAL_GND..1
(-7175 2625);
FORCEPROP 3 LASTPIN (-7175 2675) SIG_NAME GND\g
J 0
(-7165 2685);
DISPLAY 0.659574 (-7165 2685);
PAINT MONO (-7165 2685);
DISPLAY INVISIBLE (-7165 2685);
FORCEPROP 2 LAST CDS_LIB pure_quanta_power
J 0
(-7175 2625);
DISPLAY INVISIBLE (-7175 2625);
FORCEPROP 1 LAST HDL_POWER GND
J 1
(-7150 2550);
DISPLAY 0.872340 (-7150 2550);
PAINT GREEN (-7150 2550);
DISPLAY INVISIBLE (-7150 2550);
FORCEPROP 1 LAST PATH I15
J 0
(-7100 2625);
DISPLAY 0.872340 (-7100 2625);
PAINT AQUA (-7100 2625);
DISPLAY INVISIBLE (-7100 2625);
FORCEADD OFFPAGE..1
(-7150 4150);
FORCEPROP 2 LAST $XR0 210 
J 0
(-7402 4150);
DISPLAY 0.638298 (-7402 4150);
PAINT MONO (-7402 4150);
FORCEPROP 2 LAST CDS_LIB standard
J 2
(-7150 4150);
DISPLAY INVISIBLE (-7150 4150);
FORCEPROP 1 LAST OFFPAGE TRUE
J 0
(-6825 4025);
DISPLAY 0.872340 (-6825 4025);
PAINT GREEN (-6825 4025);
DISPLAY INVISIBLE (-6825 4025);
FORCEPROP 1 LAST COMMENT_BODY TRUE
J 0
(-7025 4050);
DISPLAY 0.872340 (-7025 4050);
PAINT GREEN (-7025 4050);
DISPLAY INVISIBLE (-7025 4050);
FORCEPROP 2 LAST PATH I16
J 0
(-7425 4200);
DISPLAY 0.680851 (-7425 4200);
DISPLAY INVISIBLE (-7425 4200);
FORCEADD ISL99390FRZTR5935..1
(-6050 4750);
FORCEPROP 1 LAST LOCATION PU30
J 0
(-6350 5625);
DISPLAY 0.489362 (-6350 5625);
PAINT SKYBLUE (-6350 5625);
FORCEPROP 2 LAST $SEC 1
J 0
(-6350 5775);
DISPLAY 0.680851 (-6350 5775);
PAINT MONO (-6350 5775);
DISPLAY INVISIBLE (-6350 5775);
FORCEPROP 2 LAST CDS_SEC 1
J 0
(-6350 5775);
DISPLAY 1.021277 (-6350 5775);
DISPLAY INVISIBLE (-6350 5775);
FORCEPROP 2 LASTPIN (-5650 4300) $PN 2
J 0
(-5640 4310);
DISPLAY 0.489362 (-5640 4310);
PAINT MONO (-5640 4310);
FORCEPROP 2 LASTPIN (-5650 5100) $PN 33
J 0
(-5640 5110);
DISPLAY 0.489362 (-5640 5110);
PAINT MONO (-5640 5110);
FORCEPROP 2 LASTPIN (-6500 4500) $PN 31
J 2
(-6510 4510);
DISPLAY 0.489362 (-6510 4510);
PAINT MONO (-6510 4510);
FORCEPROP 2 LASTPIN (-6500 4900) $PN 35
J 2
(-6510 4910);
DISPLAY 0.489362 (-6510 4910);
PAINT MONO (-6510 4910);
FORCEPROP 2 LASTPIN (-5650 4450) $PN 6
J 0
(-5640 4460);
DISPLAY 0.489362 (-5640 4460);
PAINT MONO (-5640 4460);
FORCEPROP 2 LASTPIN (-5650 4400) $PN 41
J 0
(-5640 4410);
DISPLAY 0.489362 (-5640 4410);
PAINT MONO (-5640 4410);
FORCEPROP 2 LASTPIN (-6500 4750) $PN 38
J 2
(-6510 4760);
DISPLAY 0.489362 (-6510 4760);
PAINT MONO (-6510 4760);
FORCEPROP 2 LASTPIN (-6500 4450) $PN 37
J 2
(-6510 4460);
DISPLAY 0.489362 (-6510 4460);
PAINT MONO (-6510 4460);
FORCEPROP 2 LASTPIN (-5650 4250) $PN 5
J 0
(-5640 4260);
DISPLAY 0.489362 (-5640 4260);
PAINT MONO (-5640 4260);
FORCEPROP 2 LASTPIN (-5650 4200) $PN 7_9-20_24
J 0
(-5640 4210);
DISPLAY 0.489362 (-5640 4210);
PAINT MONO (-5640 4210);
FORCEPROP 2 LASTPIN (-5650 4150) $PN 40
J 0
(-5640 4160);
DISPLAY 0.489362 (-5640 4160);
PAINT MONO (-5640 4160);
FORCEPROP 2 LASTPIN (-5650 4850) $PN 32
J 0
(-5640 4860);
DISPLAY 0.489362 (-5640 4860);
PAINT MONO (-5640 4860);
FORCEPROP 2 LASTPIN (-6500 5400) $PN 4
J 2
(-6510 5410);
DISPLAY 0.489362 (-6510 5410);
PAINT MONO (-6510 5410);
FORCEPROP 2 LASTPIN (-6500 4150) $PN 34
J 2
(-6510 4160);
DISPLAY 0.489362 (-6510 4160);
PAINT MONO (-6510 4160);
FORCEPROP 2 LASTPIN (-6500 4650) $PN 39
J 2
(-6510 4660);
DISPLAY 0.489362 (-6510 4660);
PAINT MONO (-6510 4660);
FORCEPROP 2 LASTPIN (-5650 4750) $PN 10_19
J 0
(-5640 4760);
DISPLAY 0.489362 (-5640 4760);
PAINT MONO (-5640 4760);
FORCEPROP 2 LASTPIN (-6500 4250) $PN 36
J 2
(-6510 4260);
DISPLAY 0.489362 (-6510 4260);
PAINT MONO (-6510 4260);
FORCEPROP 2 LASTPIN (-6500 5100) $PN 3
J 2
(-6510 5110);
DISPLAY 0.489362 (-6510 5110);
PAINT MONO (-6510 5110);
FORCEPROP 2 LASTPIN (-5650 5400) $PN 25_29
J 0
(-5640 5410);
DISPLAY 0.489362 (-5640 5410);
PAINT MONO (-5640 5410);
FORCEPROP 2 LASTPIN (-5650 5350) $PN 30
J 0
(-5640 5360);
DISPLAY 0.489362 (-5640 5360);
PAINT MONO (-5640 5360);
FORCEPROP 2 LASTPIN (-5650 4500) $PN 1
J 0
(-5640 4510);
DISPLAY 0.489362 (-5640 4510);
PAINT MONO (-5640 4510);
FORCEPROP 2 LAST PART_TYPE SMLF
J 0
(-6350 5725);
DISPLAY 1.021277 (-6350 5725);
FORCEPROP 1 LAST MATERIAL IC
J 0
(-6350 5475);
DISPLAY 0.489362 (-6350 5475);
PAINT SKYBLUE (-6350 5475);
FORCEPROP 2 LAST VALUE ISL99390FRZ-TR5935
J 0
(-6350 5675);
DISPLAY 0.489362 (-6350 5675);
PAINT SKYBLUE (-6350 5675);
FORCEPROP 1 LAST NEEDS_NO_SIZE TRUE
J 0
(-6050 4750);
DISPLAY 0.723404 (-6050 4750);
PAINT GREEN (-6050 4750);
DISPLAY INVISIBLE (-6050 4750);
FORCEPROP 1 LAST CDS_LMAN_SYM_OUTLINE -300,700,250,-650
J 0
(-6050 4750);
DISPLAY 0.468085 (-6050 4750);
PAINT GREEN (-6050 4750);
DISPLAY INVISIBLE (-6050 4750);
FORCEPROP 2 LAST CDS_LIB pure_quanta
J 0
(-6050 4750);
DISPLAY INVISIBLE (-6050 4750);
FORCEPROP 1 LAST PATH I17
J 0
(-6050 4750);
DISPLAY 0.723404 (-6050 4750);
PAINT GREEN (-6050 4750);
DISPLAY INVISIBLE (-6050 4750);
FORCEPROP 1 LAST PART_NUMBER AL099390004
J 0
(-6350 5550);
DISPLAY 0.489362 (-6350 5550);
PAINT SKYBLUE (-6350 5550);
DISPLAY INVISIBLE (-6350 5550);
FORCEADD UNIVERSAL_GND..1
(-5450 1275);
FORCEPROP 3 LASTPIN (-5450 1325) SIG_NAME GND\g
J 0
(-5440 1335);
DISPLAY 0.659574 (-5440 1335);
PAINT MONO (-5440 1335);
DISPLAY INVISIBLE (-5440 1335);
FORCEPROP 2 LAST CDS_LIB pure_quanta_power
J 0
(-5450 1275);
DISPLAY INVISIBLE (-5450 1275);
FORCEPROP 1 LAST HDL_POWER GND
J 1
(-5425 1200);
DISPLAY 0.872340 (-5425 1200);
PAINT GREEN (-5425 1200);
DISPLAY INVISIBLE (-5425 1200);
FORCEPROP 1 LAST PATH I18
J 0
(-5375 1275);
DISPLAY 0.872340 (-5375 1275);
PAINT AQUA (-5375 1275);
DISPLAY INVISIBLE (-5375 1275);
FORCEADD UNIVERSAL_GND..1
(-4625 1000);
FORCEPROP 3 LASTPIN (-4625 1050) SIG_NAME GND\g
J 0
(-4615 1060);
DISPLAY 0.659574 (-4615 1060);
PAINT MONO (-4615 1060);
DISPLAY INVISIBLE (-4615 1060);
FORCEPROP 2 LAST CDS_LIB pure_quanta_power
J 0
(-4625 1000);
DISPLAY INVISIBLE (-4625 1000);
FORCEPROP 1 LAST HDL_POWER GND
J 1
(-4600 925);
DISPLAY 0.872340 (-4600 925);
PAINT GREEN (-4600 925);
DISPLAY INVISIBLE (-4600 925);
FORCEPROP 1 LAST PATH I19
J 0
(-4550 1000);
DISPLAY 0.872340 (-4550 1000);
PAINT AQUA (-4550 1000);
DISPLAY INVISIBLE (-4550 1000);
FORCEADD OFFPAGE..1
(-8100 4650);
FORCEPROP 2 LAST $XR5 216 
J 0
(-8952 4650);
DISPLAY 0.638298 (-8952 4650);
PAINT MONO (-8952 4650);
FORCEPROP 2 LAST $XR4 215 
J 0
(-8832 4650);
DISPLAY 0.638298 (-8832 4650);
PAINT MONO (-8832 4650);
FORCEPROP 2 LAST $XR3 213 
J 0
(-8712 4650);
DISPLAY 0.638298 (-8712 4650);
PAINT MONO (-8712 4650);
FORCEPROP 2 LAST $XR2 212 
J 0
(-8592 4650);
DISPLAY 0.638298 (-8592 4650);
PAINT MONO (-8592 4650);
FORCEPROP 2 LAST $XR1 211 
J 0
(-8472 4650);
DISPLAY 0.638298 (-8472 4650);
PAINT MONO (-8472 4650);
FORCEPROP 2 LAST $XR0 210 
J 0
(-8352 4650);
DISPLAY 0.638298 (-8352 4650);
PAINT MONO (-8352 4650);
FORCEPROP 2 LAST CDS_LIB standard
J 0
(-8100 4650);
DISPLAY INVISIBLE (-8100 4650);
FORCEPROP 1 LAST OFFPAGE TRUE
J 0
(-7775 4525);
DISPLAY 0.872340 (-7775 4525);
PAINT GREEN (-7775 4525);
DISPLAY INVISIBLE (-7775 4525);
FORCEPROP 1 LAST COMMENT_BODY TRUE
J 0
(-7975 4550);
DISPLAY 0.872340 (-7975 4550);
PAINT GREEN (-7975 4550);
DISPLAY INVISIBLE (-7975 4550);
FORCEPROP 2 LAST PATH I2
J 0
(-8350 4700);
DISPLAY 0.680851 (-8350 4700);
DISPLAY INVISIBLE (-8350 4700);
FORCEADD Q_CAP..1
(-4625 1775);
FORCEPROP 1 LAST LOCATION PC149
J 0
(-4575 1875);
DISPLAY 0.489362 (-4575 1875);
PAINT SKYBLUE (-4575 1875);
FORCEPROP 0 LAST $SEC 1
J 0
(-4575 1925);
DISPLAY 0.680851 (-4575 1925);
PAINT MONO (-4575 1925);
DISPLAY INVISIBLE (-4575 1925);
FORCEPROP 0 LAST CDS_SEC 1
J 0
(-4575 1925);
DISPLAY 1.021277 (-4575 1925);
DISPLAY INVISIBLE (-4575 1925);
FORCEPROP 1 LASTPIN (-4625 1875) $PN 1
J 0
(-4615 1855);
DISPLAY 0.489362 (-4615 1855);
PAINT MONO (-4615 1855);
FORCEPROP 1 LASTPIN (-4625 1675) $PN 2
J 0
(-4615 1655);
DISPLAY 0.489362 (-4615 1655);
PAINT MONO (-4615 1655);
FORCEPROP 1 LAST PACK_TYPE C0402
J 0
(-4575 1575);
DISPLAY 0.489362 (-4575 1575);
PAINT SKYBLUE (-4575 1575);
FORCEPROP 1 LAST VOLTAGE 50V
J 0
(-4575 1775);
DISPLAY 0.489362 (-4575 1775);
PAINT SKYBLUE (-4575 1775);
FORCEPROP 1 LAST VALUE 560PF
J 0
(-4575 1825);
DISPLAY 0.489362 (-4575 1825);
PAINT SKYBLUE (-4575 1825);
FORCEPROP 1 LAST TOLERANCE 10%
J 0
(-4575 1725);
DISPLAY 0.489362 (-4575 1725);
PAINT SKYBLUE (-4575 1725);
FORCEPROP 1 LAST MATERIAL EMPTY
J 0
(-4575 1675);
DISPLAY 0.489362 (-4575 1675);
PAINT RED (-4575 1675);
FORCEPROP 2 LAST CDS_LIB pure_quanta
J 0
(-4625 1775);
DISPLAY INVISIBLE (-4625 1775);
FORCEPROP 1 LAST PATH I20
J 0
(-4575 1925);
DISPLAY 0.978723 (-4575 1925);
PAINT WHITE (-4575 1925);
DISPLAY INVISIBLE (-4575 1925);
FORCEPROP 1 LAST PART_NUMBER CH1566K1B09
J 0
(-4575 1625);
DISPLAY 0.489362 (-4575 1625);
PAINT SKYBLUE (-4575 1625);
DISPLAY INVISIBLE (-4575 1625);
FORCEADD Q_RES..2
(-4625 1225);
FORCEPROP 1 LAST LOCATION PR526
J 0
(-4580 1350);
DISPLAY 0.489362 (-4580 1350);
PAINT SKYBLUE (-4580 1350);
FORCEPROP 0 LAST $SEC 1
J 0
(-4575 1400);
DISPLAY 0.680851 (-4575 1400);
PAINT MONO (-4575 1400);
DISPLAY INVISIBLE (-4575 1400);
FORCEPROP 0 LAST CDS_SEC 1
J 0
(-4575 1400);
DISPLAY 1.021277 (-4575 1400);
DISPLAY INVISIBLE (-4575 1400);
FORCEPROP 1 LASTPIN (-4625 1325) $PN 1
J 0
(-4620 1287);
DISPLAY 0.489362 (-4620 1287);
PAINT MONO (-4620 1287);
FORCEPROP 1 LASTPIN (-4625 1125) $PN 2
J 0
(-4620 1135);
DISPLAY 0.489362 (-4620 1135);
PAINT MONO (-4620 1135);
FORCEPROP 1 LAST PACK_TYPE 0402LF
J 0
(-4585 1050);
DISPLAY 0.489362 (-4585 1050);
PAINT SKYBLUE (-4585 1050);
FORCEPROP 1 LAST VALUE 1.5
J 0
(-4580 1300);
DISPLAY 0.489362 (-4580 1300);
PAINT SKYBLUE (-4580 1300);
FORCEPROP 1 LAST TOLERANCE 1%
J 0
(-4580 1250);
DISPLAY 0.489362 (-4580 1250);
PAINT SKYBLUE (-4580 1250);
FORCEPROP 1 LAST MATERIAL EMPTY
J 0
(-4585 1150);
DISPLAY 0.489362 (-4585 1150);
PAINT RED (-4585 1150);
FORCEPROP 1 LAST WATTAGE 1/8W
J 0
(-4585 1200);
DISPLAY 0.489362 (-4585 1200);
PAINT SKYBLUE (-4585 1200);
FORCEPROP 2 LAST CDS_LIB pure_quanta
J 0
(-4625 1225);
DISPLAY INVISIBLE (-4625 1225);
FORCEPROP 1 LAST PATH I21
J 0
(-4575 1400);
DISPLAY 0.978723 (-4575 1400);
PAINT WHITE (-4575 1400);
DISPLAY INVISIBLE (-4575 1400);
FORCEPROP 1 LAST PART_NUMBER CS-1504FB00
J 0
(-4585 1100);
DISPLAY 0.489362 (-4585 1100);
PAINT SKYBLUE (-4585 1100);
DISPLAY INVISIBLE (-4585 1100);
FORCEADD Q_CAP..1
(-5375 2875);
FORCEPROP 1 LAST LOCATION PC326_2
J 0
(-5325 2975);
DISPLAY 0.489362 (-5325 2975);
PAINT SKYBLUE (-5325 2975);
FORCEPROP 0 LAST $SEC 1
J 0
(-5325 3025);
DISPLAY 0.680851 (-5325 3025);
PAINT MONO (-5325 3025);
DISPLAY INVISIBLE (-5325 3025);
FORCEPROP 0 LAST CDS_SEC 1
J 0
(-5325 3025);
DISPLAY 1.021277 (-5325 3025);
DISPLAY INVISIBLE (-5325 3025);
FORCEPROP 1 LASTPIN (-5375 2975) $PN 1
J 0
(-5365 2955);
DISPLAY 0.489362 (-5365 2955);
PAINT MONO (-5365 2955);
FORCEPROP 1 LASTPIN (-5375 2775) $PN 2
J 0
(-5365 2755);
DISPLAY 0.489362 (-5365 2755);
PAINT MONO (-5365 2755);
FORCEPROP 1 LAST VALUE 0.1UF
J 0
(-5325 2925);
DISPLAY 0.489362 (-5325 2925);
PAINT SKYBLUE (-5325 2925);
FORCEPROP 1 LAST VOLTAGE 25V
J 0
(-5325 2875);
DISPLAY 0.489362 (-5325 2875);
PAINT SKYBLUE (-5325 2875);
FORCEPROP 1 LAST PACK_TYPE 0402
J 0
(-5325 2675);
DISPLAY 0.489362 (-5325 2675);
PAINT SKYBLUE (-5325 2675);
FORCEPROP 1 LAST TOLERANCE 10%
J 0
(-5325 2825);
DISPLAY 0.489362 (-5325 2825);
PAINT SKYBLUE (-5325 2825);
FORCEPROP 1 LAST MATERIAL X7R
J 0
(-5325 2775);
DISPLAY 0.489362 (-5325 2775);
PAINT SKYBLUE (-5325 2775);
FORCEPROP 2 LAST CDS_LIB pure_quanta
J 0
(-5375 2875);
DISPLAY INVISIBLE (-5375 2875);
FORCEPROP 1 LAST PATH I22
J 0
(-5325 3025);
DISPLAY 0.978723 (-5325 3025);
PAINT WHITE (-5325 3025);
DISPLAY INVISIBLE (-5325 3025);
FORCEPROP 1 LAST PART_NUMBER CH4104K1B00
J 0
(-5325 2725);
DISPLAY 0.489362 (-5325 2725);
PAINT SKYBLUE (-5325 2725);
DISPLAY INVISIBLE (-5325 2725);
FORCEADD UNIVERSAL_GND..1
(-5475 4025);
FORCEPROP 3 LASTPIN (-5475 4075) SIG_NAME GND\g
J 0
(-5465 4085);
DISPLAY 0.659574 (-5465 4085);
PAINT MONO (-5465 4085);
DISPLAY INVISIBLE (-5465 4085);
FORCEPROP 2 LAST CDS_LIB pure_quanta_power
J 0
(-5475 4025);
DISPLAY INVISIBLE (-5475 4025);
FORCEPROP 1 LAST HDL_POWER GND
J 1
(-5450 3950);
DISPLAY 0.872340 (-5450 3950);
PAINT GREEN (-5450 3950);
DISPLAY INVISIBLE (-5450 3950);
FORCEPROP 1 LAST PATH I23
J 0
(-5400 4025);
DISPLAY 0.872340 (-5400 4025);
PAINT AQUA (-5400 4025);
DISPLAY INVISIBLE (-5400 4025);
FORCEADD Q_RES..1
(-4700 2325);
FORCEPROP 1 LAST LOCATION PR210
J 0
(-4725 2375);
DISPLAY 0.489362 (-4725 2375);
PAINT SKYBLUE (-4725 2375);
FORCEPROP 0 LAST $SEC 1
J 0
(-4675 2400);
DISPLAY 0.680851 (-4675 2400);
PAINT MONO (-4675 2400);
DISPLAY INVISIBLE (-4675 2400);
FORCEPROP 0 LAST CDS_SEC 1
J 0
(-4675 2400);
DISPLAY 1.021277 (-4675 2400);
DISPLAY INVISIBLE (-4675 2400);
FORCEPROP 1 LASTPIN (-4800 2325) $PN 1
J 0
(-4788 2337);
DISPLAY 0.489362 (-4788 2337);
PAINT MONO (-4788 2337);
FORCEPROP 1 LASTPIN (-4600 2325) $PN 2
J 0
(-4638 2337);
DISPLAY 0.489362 (-4638 2337);
PAINT MONO (-4638 2337);
FORCEPROP 1 LAST WATTAGE 1/16W
J 0
(-4600 2275);
DISPLAY 0.489362 (-4600 2275);
PAINT SKYBLUE (-4600 2275);
FORCEPROP 1 LAST PACK_TYPE 0402LF
J 0
(-4600 2225);
DISPLAY 0.489362 (-4600 2225);
PAINT SKYBLUE (-4600 2225);
FORCEPROP 1 LAST MATERIAL CHIP
J 0
(-4950 2225);
DISPLAY 0.489362 (-4950 2225);
PAINT SKYBLUE (-4950 2225);
FORCEPROP 1 LAST TOLERANCE 1%
J 0
(-4575 2350);
DISPLAY 0.489362 (-4575 2350);
PAINT SKYBLUE (-4575 2350);
FORCEPROP 1 LAST VALUE 5.6
J 2
(-4825 2350);
DISPLAY 0.489362 (-4825 2350);
PAINT SKYBLUE (-4825 2350);
FORCEPROP 2 LAST CDS_LIB pure_quanta
J 0
(-4700 2325);
DISPLAY INVISIBLE (-4700 2325);
FORCEPROP 1 LAST PATH I24
J 0
(-4750 2475);
DISPLAY 0.978723 (-4750 2475);
PAINT WHITE (-4750 2475);
DISPLAY INVISIBLE (-4750 2475);
FORCEPROP 1 LAST PART_NUMBER CS-5602FB01
J 0
(-4950 2275);
DISPLAY 0.489362 (-4950 2275);
PAINT SKYBLUE (-4950 2275);
DISPLAY INVISIBLE (-4950 2275);
FORCEADD Q_CAP..1
(-5000 2875);
FORCEPROP 1 LAST LOCATION PC324_2
J 0
(-4950 2975);
DISPLAY 0.489362 (-4950 2975);
PAINT SKYBLUE (-4950 2975);
FORCEPROP 0 LAST $SEC 1
J 0
(-4950 3000);
DISPLAY 0.680851 (-4950 3000);
PAINT MONO (-4950 3000);
DISPLAY INVISIBLE (-4950 3000);
FORCEPROP 0 LAST CDS_SEC 1
J 0
(-4950 3000);
DISPLAY 1.021277 (-4950 3000);
DISPLAY INVISIBLE (-4950 3000);
FORCEPROP 1 LASTPIN (-5000 2975) $PN 1
J 0
(-4990 2955);
DISPLAY 0.489362 (-4990 2955);
PAINT MONO (-4990 2955);
FORCEPROP 1 LASTPIN (-5000 2775) $PN 2
J 0
(-4990 2755);
DISPLAY 0.489362 (-4990 2755);
PAINT MONO (-4990 2755);
FORCEPROP 1 LAST VOLTAGE 25V
J 0
(-4950 2875);
DISPLAY 0.489362 (-4950 2875);
PAINT SKYBLUE (-4950 2875);
FORCEPROP 1 LAST PACK_TYPE C0402
J 0
(-4950 2675);
DISPLAY 0.489362 (-4950 2675);
PAINT SKYBLUE (-4950 2675);
FORCEPROP 1 LAST VALUE 1UF
J 0
(-4950 2925);
DISPLAY 0.489362 (-4950 2925);
PAINT SKYBLUE (-4950 2925);
FORCEPROP 1 LAST MATERIAL X6S
J 0
(-4950 2775);
DISPLAY 0.489362 (-4950 2775);
PAINT SKYBLUE (-4950 2775);
FORCEPROP 1 LAST TOLERANCE 10%
J 0
(-4950 2825);
DISPLAY 0.489362 (-4950 2825);
PAINT SKYBLUE (-4950 2825);
FORCEPROP 2 LAST CDS_LIB pure_quanta
J 0
(-5000 2875);
DISPLAY INVISIBLE (-5000 2875);
FORCEPROP 1 LAST PATH I25
J 0
(-4950 3025);
DISPLAY 0.978723 (-4950 3025);
PAINT WHITE (-4950 3025);
DISPLAY INVISIBLE (-4950 3025);
FORCEPROP 1 LAST PART_NUMBER CH5104KEB02
J 0
(-4950 2725);
DISPLAY 0.489362 (-4950 2725);
PAINT SKYBLUE (-4950 2725);
DISPLAY INVISIBLE (-4950 2725);
FORCEADD Q_CAP..1
(-4675 2875);
FORCEPROP 1 LAST LOCATION PC328_2
J 0
(-4625 2975);
DISPLAY 0.489362 (-4625 2975);
PAINT SKYBLUE (-4625 2975);
FORCEPROP 0 LAST $SEC 1
J 0
(-4625 3000);
DISPLAY 0.680851 (-4625 3000);
PAINT MONO (-4625 3000);
DISPLAY INVISIBLE (-4625 3000);
FORCEPROP 0 LAST CDS_SEC 1
J 0
(-4625 3000);
DISPLAY 1.021277 (-4625 3000);
DISPLAY INVISIBLE (-4625 3000);
FORCEPROP 1 LASTPIN (-4675 2975) $PN 1
J 0
(-4665 2955);
DISPLAY 0.489362 (-4665 2955);
PAINT MONO (-4665 2955);
FORCEPROP 1 LASTPIN (-4675 2775) $PN 2
J 0
(-4665 2755);
DISPLAY 0.489362 (-4665 2755);
PAINT MONO (-4665 2755);
FORCEPROP 1 LAST MATERIAL X6S
J 0
(-4625 2775);
DISPLAY 0.489362 (-4625 2775);
PAINT SKYBLUE (-4625 2775);
FORCEPROP 1 LAST TOLERANCE 20%
J 0
(-4625 2825);
DISPLAY 0.489362 (-4625 2825);
PAINT SKYBLUE (-4625 2825);
FORCEPROP 1 LAST PACK_TYPE C0805
J 0
(-4625 2675);
DISPLAY 0.489362 (-4625 2675);
PAINT SKYBLUE (-4625 2675);
FORCEPROP 1 LAST VOLTAGE 16V
J 0
(-4625 2875);
DISPLAY 0.489362 (-4625 2875);
PAINT SKYBLUE (-4625 2875);
FORCEPROP 1 LAST VALUE 22UF
J 0
(-4625 2925);
DISPLAY 0.489362 (-4625 2925);
PAINT SKYBLUE (-4625 2925);
FORCEPROP 2 LAST CDS_LIB pure_quanta
J 0
(-4675 2875);
DISPLAY INVISIBLE (-4675 2875);
FORCEPROP 1 LAST PATH I26
J 0
(-4625 3025);
DISPLAY 0.978723 (-4625 3025);
PAINT WHITE (-4625 3025);
DISPLAY INVISIBLE (-4625 3025);
FORCEPROP 1 LAST PART_NUMBER CH6223MEA01
J 0
(-4625 2725);
DISPLAY 0.489362 (-4625 2725);
PAINT SKYBLUE (-4625 2725);
DISPLAY INVISIBLE (-4625 2725);
FORCEADD Q_CAP..1
(-4350 2875);
FORCEPROP 1 LAST LOCATION PC330_2
J 0
(-4300 2975);
DISPLAY 0.489362 (-4300 2975);
PAINT SKYBLUE (-4300 2975);
FORCEPROP 0 LAST $SEC 1
J 0
(-4300 3000);
DISPLAY 0.680851 (-4300 3000);
PAINT MONO (-4300 3000);
DISPLAY INVISIBLE (-4300 3000);
FORCEPROP 0 LAST CDS_SEC 1
J 0
(-4300 3000);
DISPLAY 1.021277 (-4300 3000);
DISPLAY INVISIBLE (-4300 3000);
FORCEPROP 1 LASTPIN (-4350 2975) $PN 1
J 0
(-4340 2955);
DISPLAY 0.489362 (-4340 2955);
PAINT MONO (-4340 2955);
FORCEPROP 1 LASTPIN (-4350 2775) $PN 2
J 0
(-4340 2755);
DISPLAY 0.489362 (-4340 2755);
PAINT MONO (-4340 2755);
FORCEPROP 1 LAST VOLTAGE 16V
J 0
(-4300 2875);
DISPLAY 0.489362 (-4300 2875);
PAINT SKYBLUE (-4300 2875);
FORCEPROP 1 LAST TOLERANCE 20%
J 0
(-4300 2825);
DISPLAY 0.489362 (-4300 2825);
PAINT SKYBLUE (-4300 2825);
FORCEPROP 1 LAST MATERIAL X6S
J 0
(-4300 2775);
DISPLAY 0.489362 (-4300 2775);
PAINT SKYBLUE (-4300 2775);
FORCEPROP 1 LAST VALUE 22UF
J 0
(-4300 2925);
DISPLAY 0.489362 (-4300 2925);
PAINT SKYBLUE (-4300 2925);
FORCEPROP 1 LAST PACK_TYPE C0805
J 0
(-4300 2675);
DISPLAY 0.489362 (-4300 2675);
PAINT SKYBLUE (-4300 2675);
FORCEPROP 2 LAST CDS_LIB pure_quanta
J 0
(-4350 2875);
DISPLAY INVISIBLE (-4350 2875);
FORCEPROP 1 LAST PATH I27
J 0
(-4300 3025);
DISPLAY 0.978723 (-4300 3025);
PAINT WHITE (-4300 3025);
DISPLAY INVISIBLE (-4300 3025);
FORCEPROP 1 LAST PART_NUMBER CH6223MEA01
J 0
(-4300 2725);
DISPLAY 0.489362 (-4300 2725);
PAINT SKYBLUE (-4300 2725);
DISPLAY INVISIBLE (-4300 2725);
FORCEADD UNIVERSAL_GND..1
(-4700 3825);
FORCEPROP 3 LASTPIN (-4700 3875) SIG_NAME GND\g
J 0
(-4690 3885);
DISPLAY 0.659574 (-4690 3885);
PAINT MONO (-4690 3885);
DISPLAY INVISIBLE (-4690 3885);
FORCEPROP 2 LAST CDS_LIB pure_quanta_power
J 0
(-4700 3825);
DISPLAY INVISIBLE (-4700 3825);
FORCEPROP 1 LAST HDL_POWER GND
J 1
(-4675 3750);
DISPLAY 0.872340 (-4675 3750);
PAINT GREEN (-4675 3750);
DISPLAY INVISIBLE (-4675 3750);
FORCEPROP 1 LAST PATH I28
J 0
(-4625 3825);
DISPLAY 0.872340 (-4625 3825);
PAINT AQUA (-4625 3825);
DISPLAY INVISIBLE (-4625 3825);
FORCEADD Q_RES..2
(-4700 4050);
FORCEPROP 1 LAST LOCATION PR525
J 0
(-4655 4175);
DISPLAY 0.489362 (-4655 4175);
PAINT SKYBLUE (-4655 4175);
FORCEPROP 0 LAST $SEC 1
J 0
(-4650 4225);
DISPLAY 0.680851 (-4650 4225);
PAINT MONO (-4650 4225);
DISPLAY INVISIBLE (-4650 4225);
FORCEPROP 0 LAST CDS_SEC 1
J 0
(-4650 4225);
DISPLAY 1.021277 (-4650 4225);
DISPLAY INVISIBLE (-4650 4225);
FORCEPROP 1 LASTPIN (-4700 4150) $PN 1
J 0
(-4695 4112);
DISPLAY 0.489362 (-4695 4112);
PAINT MONO (-4695 4112);
FORCEPROP 1 LASTPIN (-4700 3950) $PN 2
J 0
(-4695 3960);
DISPLAY 0.489362 (-4695 3960);
PAINT MONO (-4695 3960);
FORCEPROP 1 LAST TOLERANCE 1%
J 0
(-4655 4075);
DISPLAY 0.489362 (-4655 4075);
PAINT SKYBLUE (-4655 4075);
FORCEPROP 1 LAST WATTAGE 1/8W
J 0
(-4660 4025);
DISPLAY 0.489362 (-4660 4025);
PAINT SKYBLUE (-4660 4025);
FORCEPROP 1 LAST VALUE 1.5
J 0
(-4655 4125);
DISPLAY 0.489362 (-4655 4125);
PAINT SKYBLUE (-4655 4125);
FORCEPROP 1 LAST MATERIAL EMPTY
J 0
(-4660 3975);
DISPLAY 0.489362 (-4660 3975);
PAINT RED (-4660 3975);
FORCEPROP 1 LAST PACK_TYPE 0402LF
J 0
(-4660 3875);
DISPLAY 0.489362 (-4660 3875);
PAINT SKYBLUE (-4660 3875);
FORCEPROP 2 LAST CDS_LIB pure_quanta
J 0
(-4700 4050);
DISPLAY INVISIBLE (-4700 4050);
FORCEPROP 1 LAST PATH I29
J 0
(-4650 4225);
DISPLAY 0.978723 (-4650 4225);
PAINT WHITE (-4650 4225);
DISPLAY INVISIBLE (-4650 4225);
FORCEPROP 1 LAST PART_NUMBER CS-1504FB00
J 0
(-4660 3925);
DISPLAY 0.489362 (-4660 3925);
PAINT SKYBLUE (-4660 3925);
DISPLAY INVISIBLE (-4660 3925);
FORCEADD UNIVERSAL_GND..1
(-7850 1425);
FORCEPROP 3 LASTPIN (-7850 1475) SIG_NAME GND\g
J 0
(-7840 1485);
DISPLAY 0.659574 (-7840 1485);
PAINT MONO (-7840 1485);
DISPLAY INVISIBLE (-7840 1485);
FORCEPROP 2 LAST CDS_LIB pure_quanta_power
J 0
(-7850 1425);
DISPLAY INVISIBLE (-7850 1425);
FORCEPROP 1 LAST HDL_POWER GND
J 1
(-7825 1350);
DISPLAY 0.872340 (-7825 1350);
PAINT GREEN (-7825 1350);
DISPLAY INVISIBLE (-7825 1350);
FORCEPROP 1 LAST PATH I3
J 0
(-7775 1425);
DISPLAY 0.872340 (-7775 1425);
PAINT AQUA (-7775 1425);
DISPLAY INVISIBLE (-7775 1425);
FORCEADD Q_RES..1
(-4225 3725);
FORCEPROP 1 LAST LOCATION PR211
J 0
(-4275 3775);
DISPLAY 0.489362 (-4275 3775);
PAINT SKYBLUE (-4275 3775);
FORCEPROP 0 LAST $SEC 1
J 0
(-4225 3800);
DISPLAY 0.680851 (-4225 3800);
PAINT MONO (-4225 3800);
DISPLAY INVISIBLE (-4225 3800);
FORCEPROP 0 LAST CDS_SEC 1
J 0
(-4225 3800);
DISPLAY 1.021277 (-4225 3800);
DISPLAY INVISIBLE (-4225 3800);
FORCEPROP 1 LASTPIN (-4325 3725) $PN 1
J 0
(-4313 3737);
DISPLAY 0.489362 (-4313 3737);
PAINT MONO (-4313 3737);
FORCEPROP 1 LASTPIN (-4125 3725) $PN 2
J 0
(-4163 3737);
DISPLAY 0.489362 (-4163 3737);
PAINT MONO (-4163 3737);
FORCEPROP 1 LAST VALUE 0
J 2
(-4350 3750);
DISPLAY 0.489362 (-4350 3750);
PAINT SKYBLUE (-4350 3750);
FORCEPROP 1 LAST WATTAGE 1/16W
J 0
(-4125 3675);
DISPLAY 0.489362 (-4125 3675);
PAINT SKYBLUE (-4125 3675);
FORCEPROP 1 LAST TOLERANCE 5%
J 0
(-4100 3750);
DISPLAY 0.489362 (-4100 3750);
PAINT SKYBLUE (-4100 3750);
FORCEPROP 1 LAST PACK_TYPE 0402LF
J 0
(-4125 3625);
DISPLAY 0.489362 (-4125 3625);
PAINT SKYBLUE (-4125 3625);
FORCEPROP 1 LAST MATERIAL CHIP
J 0
(-4475 3625);
DISPLAY 0.489362 (-4475 3625);
PAINT SKYBLUE (-4475 3625);
FORCEPROP 2 LAST CDS_LIB pure_quanta
J 0
(-4225 3725);
DISPLAY INVISIBLE (-4225 3725);
FORCEPROP 1 LAST PATH I30
J 0
(-4275 3875);
DISPLAY 0.978723 (-4275 3875);
PAINT WHITE (-4275 3875);
DISPLAY INVISIBLE (-4275 3875);
FORCEPROP 1 LAST PART_NUMBER CS00002JB13
J 0
(-4475 3675);
DISPLAY 0.489362 (-4475 3675);
PAINT SKYBLUE (-4475 3675);
DISPLAY INVISIBLE (-4475 3675);
FORCEADD UNIVERSAL_GND..1
(-7875 4200);
FORCEPROP 3 LASTPIN (-7875 4250) SIG_NAME GND\g
J 0
(-7865 4260);
DISPLAY 0.659574 (-7865 4260);
PAINT MONO (-7865 4260);
DISPLAY INVISIBLE (-7865 4260);
FORCEPROP 2 LAST CDS_LIB pure_quanta_power
J 0
(-7875 4200);
DISPLAY INVISIBLE (-7875 4200);
FORCEPROP 1 LAST HDL_POWER GND
J 1
(-7850 4125);
DISPLAY 0.872340 (-7850 4125);
PAINT GREEN (-7850 4125);
DISPLAY INVISIBLE (-7850 4125);
FORCEPROP 1 LAST PATH I31
J 0
(-7800 4200);
DISPLAY 0.872340 (-7800 4200);
PAINT AQUA (-7800 4200);
DISPLAY INVISIBLE (-7800 4200);
FORCEADD Q_CAP..1
(-7875 4475);
FORCEPROP 1 LAST LOCATION PC317_7
J 0
(-7825 4575);
DISPLAY 0.489362 (-7825 4575);
PAINT SKYBLUE (-7825 4575);
FORCEPROP 0 LAST $SEC 1
J 0
(-7825 4600);
DISPLAY 0.680851 (-7825 4600);
PAINT MONO (-7825 4600);
DISPLAY INVISIBLE (-7825 4600);
FORCEPROP 0 LAST CDS_SEC 1
J 0
(-7825 4600);
DISPLAY 1.021277 (-7825 4600);
DISPLAY INVISIBLE (-7825 4600);
FORCEPROP 1 LASTPIN (-7875 4575) $PN 1
J 0
(-7865 4555);
DISPLAY 0.489362 (-7865 4555);
PAINT MONO (-7865 4555);
FORCEPROP 1 LASTPIN (-7875 4375) $PN 2
J 0
(-7865 4355);
DISPLAY 0.489362 (-7865 4355);
PAINT MONO (-7865 4355);
FORCEPROP 1 LAST VALUE 0.1UF
J 0
(-7825 4525);
DISPLAY 0.489362 (-7825 4525);
PAINT SKYBLUE (-7825 4525);
FORCEPROP 1 LAST VOLTAGE 25V
J 0
(-7825 4475);
DISPLAY 0.489362 (-7825 4475);
PAINT SKYBLUE (-7825 4475);
FORCEPROP 1 LAST TOLERANCE 10%
J 0
(-7825 4425);
DISPLAY 0.489362 (-7825 4425);
PAINT SKYBLUE (-7825 4425);
FORCEPROP 1 LAST MATERIAL X7R
J 0
(-7825 4375);
DISPLAY 0.489362 (-7825 4375);
PAINT SKYBLUE (-7825 4375);
FORCEPROP 1 LAST PACK_TYPE 0402
J 0
(-7825 4275);
DISPLAY 0.489362 (-7825 4275);
PAINT SKYBLUE (-7825 4275);
FORCEPROP 2 LAST CDS_LIB pure_quanta
J 0
(-7875 4475);
DISPLAY INVISIBLE (-7875 4475);
FORCEPROP 1 LAST PATH I32
J 0
(-7825 4625);
DISPLAY 0.978723 (-7825 4625);
PAINT WHITE (-7825 4625);
DISPLAY INVISIBLE (-7825 4625);
FORCEPROP 1 LAST PART_NUMBER CH4104K1B00
J 0
(-7825 4325);
DISPLAY 0.489362 (-7825 4325);
PAINT SKYBLUE (-7825 4325);
DISPLAY INVISIBLE (-7825 4325);
FORCEADD UNIVERSAL_GND..1
(-7550 4275);
FORCEPROP 3 LASTPIN (-7550 4325) SIG_NAME GND\g
J 0
(-7540 4335);
DISPLAY 0.659574 (-7540 4335);
PAINT MONO (-7540 4335);
DISPLAY INVISIBLE (-7540 4335);
FORCEPROP 2 LAST CDS_LIB pure_quanta_power
J 0
(-7550 4275);
DISPLAY INVISIBLE (-7550 4275);
FORCEPROP 1 LAST HDL_POWER GND
J 1
(-7525 4200);
DISPLAY 0.872340 (-7525 4200);
PAINT GREEN (-7525 4200);
DISPLAY INVISIBLE (-7525 4200);
FORCEPROP 1 LAST PATH I33
J 0
(-7475 4275);
DISPLAY 0.872340 (-7475 4275);
PAINT AQUA (-7475 4275);
DISPLAY INVISIBLE (-7475 4275);
FORCEADD OFFPAGE..2
R 2
(-7175 4250);
FORCEPROP 2 LAST $XR2 210 
J 0
(-7550 4214);
DISPLAY 0.638298 (-7550 4214);
PAINT MONO (-7550 4214);
FORCEPROP 2 LAST $XR1 216 
J 0
(-7430 4214);
DISPLAY 0.638298 (-7430 4214);
PAINT MONO (-7430 4214);
FORCEPROP 2 LAST $XR0 215 
J 0
(-7430 4250);
DISPLAY 0.638298 (-7430 4250);
PAINT MONO (-7430 4250);
FORCEPROP 2 LAST CDS_LIB standard
J 0
(-7175 4250);
DISPLAY INVISIBLE (-7175 4250);
FORCEPROP 1 LAST OFFPAGE TRUE
J 2
(-7500 4125);
DISPLAY 0.872340 (-7500 4125);
PAINT GREEN (-7500 4125);
DISPLAY INVISIBLE (-7500 4125);
FORCEPROP 1 LAST COMMENT_BODY TRUE
J 2
(-7130 4155);
DISPLAY 0.872340 (-7130 4155);
PAINT GREEN (-7130 4155);
DISPLAY INVISIBLE (-7130 4155);
FORCEPROP 2 LAST PATH I34
J 0
(-7450 4300);
DISPLAY 0.680851 (-7450 4300);
DISPLAY INVISIBLE (-7450 4300);
FORCEADD Q_RES..1
(-7200 4450);
FORCEPROP 1 LAST LOCATION PR207
J 0
(-7225 4500);
DISPLAY 0.489362 (-7225 4500);
PAINT SKYBLUE (-7225 4500);
FORCEPROP 0 LAST $SEC 1
J 0
(-7200 4525);
DISPLAY 0.680851 (-7200 4525);
PAINT MONO (-7200 4525);
DISPLAY INVISIBLE (-7200 4525);
FORCEPROP 0 LAST CDS_SEC 1
J 0
(-7200 4525);
DISPLAY 1.021277 (-7200 4525);
DISPLAY INVISIBLE (-7200 4525);
FORCEPROP 1 LASTPIN (-7300 4450) $PN 1
J 0
(-7288 4462);
DISPLAY 0.489362 (-7288 4462);
PAINT MONO (-7288 4462);
FORCEPROP 1 LASTPIN (-7100 4450) $PN 2
J 0
(-7138 4462);
DISPLAY 0.489362 (-7138 4462);
PAINT MONO (-7138 4462);
FORCEPROP 1 LAST WATTAGE 1/16W
J 0
(-7100 4350);
DISPLAY 0.489362 (-7100 4350);
PAINT SKYBLUE (-7100 4350);
FORCEPROP 1 LAST PACK_TYPE 0402LF
J 0
(-7100 4400);
DISPLAY 0.489362 (-7100 4400);
PAINT SKYBLUE (-7100 4400);
FORCEPROP 1 LAST VALUE 8.87K
J 2
(-7325 4475);
DISPLAY 0.489362 (-7325 4475);
PAINT SKYBLUE (-7325 4475);
FORCEPROP 1 LAST TOLERANCE 1%
J 0
(-7075 4475);
DISPLAY 0.489362 (-7075 4475);
PAINT SKYBLUE (-7075 4475);
FORCEPROP 1 LAST MATERIAL EMPTY
J 0
(-7500 4350);
DISPLAY 0.489362 (-7500 4350);
PAINT RED (-7500 4350);
FORCEPROP 2 LAST CDS_LIB pure_quanta
J 0
(-7200 4450);
DISPLAY INVISIBLE (-7200 4450);
FORCEPROP 1 LAST PATH I35
J 0
(-7250 4600);
DISPLAY 0.978723 (-7250 4600);
PAINT WHITE (-7250 4600);
DISPLAY INVISIBLE (-7250 4600);
FORCEPROP 1 LAST PART_NUMBER CS28872FB01
J 0
(-7500 4400);
DISPLAY 0.489362 (-7500 4400);
PAINT SKYBLUE (-7500 4400);
DISPLAY INVISIBLE (-7500 4400);
FORCEADD Q_CAP..1
(-7550 5100);
FORCEPROP 1 LAST LOCATION PC319
J 0
(-7500 5200);
DISPLAY 0.489362 (-7500 5200);
PAINT SKYBLUE (-7500 5200);
FORCEPROP 0 LAST $SEC 1
J 0
(-7500 5250);
DISPLAY 0.680851 (-7500 5250);
PAINT MONO (-7500 5250);
DISPLAY INVISIBLE (-7500 5250);
FORCEPROP 0 LAST CDS_SEC 1
J 0
(-7500 5250);
DISPLAY 1.021277 (-7500 5250);
DISPLAY INVISIBLE (-7500 5250);
FORCEPROP 1 LASTPIN (-7550 5200) $PN 1
J 0
(-7540 5180);
DISPLAY 0.489362 (-7540 5180);
PAINT MONO (-7540 5180);
FORCEPROP 1 LASTPIN (-7550 5000) $PN 2
J 0
(-7540 4980);
DISPLAY 0.489362 (-7540 4980);
PAINT MONO (-7540 4980);
FORCEPROP 1 LAST VOLTAGE 10V
J 0
(-7500 5100);
DISPLAY 0.489362 (-7500 5100);
PAINT SKYBLUE (-7500 5100);
FORCEPROP 1 LAST PACK_TYPE C0402
J 0
(-7500 4900);
DISPLAY 0.489362 (-7500 4900);
PAINT SKYBLUE (-7500 4900);
FORCEPROP 1 LAST VALUE 2.2UF
J 0
(-7500 5150);
DISPLAY 0.489362 (-7500 5150);
PAINT SKYBLUE (-7500 5150);
FORCEPROP 1 LAST TOLERANCE 10%
J 0
(-7500 5050);
DISPLAY 0.489362 (-7500 5050);
PAINT SKYBLUE (-7500 5050);
FORCEPROP 1 LAST MATERIAL X6S
J 0
(-7500 5000);
DISPLAY 0.489362 (-7500 5000);
PAINT SKYBLUE (-7500 5000);
FORCEPROP 2 LAST CDS_LIB pure_quanta
J 0
(-7550 5100);
DISPLAY INVISIBLE (-7550 5100);
FORCEPROP 1 LAST PATH I36
J 0
(-7500 5250);
DISPLAY 0.978723 (-7500 5250);
PAINT WHITE (-7500 5250);
DISPLAY INVISIBLE (-7500 5250);
FORCEPROP 1 LAST PART_NUMBER CH5222KEB01
J 0
(-7500 4950);
DISPLAY 0.489362 (-7500 4950);
PAINT SKYBLUE (-7500 4950);
DISPLAY INVISIBLE (-7500 4950);
FORCEADD UNIVERSAL_GND..1
(-7550 4900);
FORCEPROP 3 LASTPIN (-7550 4950) SIG_NAME GND\g
J 0
(-7540 4960);
DISPLAY 0.659574 (-7540 4960);
PAINT MONO (-7540 4960);
DISPLAY INVISIBLE (-7540 4960);
FORCEPROP 2 LAST CDS_LIB pure_quanta_power
J 0
(-7550 4900);
DISPLAY INVISIBLE (-7550 4900);
FORCEPROP 1 LAST HDL_POWER GND
J 1
(-7525 4825);
DISPLAY 0.872340 (-7525 4825);
PAINT GREEN (-7525 4825);
DISPLAY INVISIBLE (-7525 4825);
FORCEPROP 1 LAST PATH I37
J 0
(-7475 4900);
DISPLAY 0.872340 (-7475 4900);
PAINT AQUA (-7475 4900);
DISPLAY INVISIBLE (-7475 4900);
FORCEADD OFFPAGE..2
R 2
(-7200 4750);
FORCEPROP 2 LAST $XR0 210 
J 0
(-7455 4750);
DISPLAY 0.638298 (-7455 4750);
PAINT MONO (-7455 4750);
FORCEPROP 2 LAST CDS_LIB standard
J 2
(-7200 4750);
DISPLAY INVISIBLE (-7200 4750);
FORCEPROP 1 LAST OFFPAGE TRUE
J 2
(-7525 4625);
DISPLAY 0.872340 (-7525 4625);
PAINT GREEN (-7525 4625);
DISPLAY INVISIBLE (-7525 4625);
FORCEPROP 1 LAST COMMENT_BODY TRUE
J 2
(-7155 4655);
DISPLAY 0.872340 (-7155 4655);
PAINT GREEN (-7155 4655);
DISPLAY INVISIBLE (-7155 4655);
FORCEPROP 2 LAST PATH I38
J 0
(-7450 4800);
DISPLAY 0.680851 (-7450 4800);
DISPLAY INVISIBLE (-7450 4800);
FORCEADD Q_RES..2
(-7550 5650);
FORCEPROP 1 LAST LOCATION PR205
J 0
(-7505 5775);
DISPLAY 0.489362 (-7505 5775);
PAINT SKYBLUE (-7505 5775);
FORCEPROP 0 LAST $SEC 1
J 0
(-7500 5825);
DISPLAY 0.680851 (-7500 5825);
PAINT MONO (-7500 5825);
DISPLAY INVISIBLE (-7500 5825);
FORCEPROP 0 LAST CDS_SEC 1
J 0
(-7500 5825);
DISPLAY 1.021277 (-7500 5825);
DISPLAY INVISIBLE (-7500 5825);
FORCEPROP 1 LASTPIN (-7550 5750) $PN 1
J 0
(-7545 5712);
DISPLAY 0.489362 (-7545 5712);
PAINT MONO (-7545 5712);
FORCEPROP 1 LASTPIN (-7550 5550) $PN 2
J 0
(-7545 5560);
DISPLAY 0.489362 (-7545 5560);
PAINT MONO (-7545 5560);
FORCEPROP 1 LAST WATTAGE 1/16W
J 0
(-7500 5625);
DISPLAY 0.489362 (-7500 5625);
PAINT SKYBLUE (-7500 5625);
FORCEPROP 1 LAST MATERIAL CHIP
J 0
(-7500 5575);
DISPLAY 0.489362 (-7500 5575);
PAINT SKYBLUE (-7500 5575);
FORCEPROP 1 LAST VALUE 2.2
J 0
(-7500 5725);
DISPLAY 0.489362 (-7500 5725);
PAINT SKYBLUE (-7500 5725);
FORCEPROP 1 LAST TOLERANCE 1%
J 0
(-7500 5675);
DISPLAY 0.489362 (-7500 5675);
PAINT SKYBLUE (-7500 5675);
FORCEPROP 1 LAST PACK_TYPE 0402LF
J 0
(-7500 5475);
DISPLAY 0.489362 (-7500 5475);
PAINT SKYBLUE (-7500 5475);
FORCEPROP 2 LAST CDS_LIB pure_quanta
J 0
(-7550 5650);
DISPLAY INVISIBLE (-7550 5650);
FORCEPROP 1 LAST PATH I39
J 0
(-7500 5825);
DISPLAY 0.978723 (-7500 5825);
PAINT WHITE (-7500 5825);
DISPLAY INVISIBLE (-7500 5825);
FORCEPROP 1 LAST PART_NUMBER CS-2202FB01
J 0
(-7500 5525);
DISPLAY 0.489362 (-7500 5525);
PAINT SKYBLUE (-7500 5525);
DISPLAY INVISIBLE (-7500 5525);
FORCEADD Q_CAP..1
(-7850 1700);
FORCEPROP 1 LAST LOCATION PC318_8
J 0
(-7800 1800);
DISPLAY 0.489362 (-7800 1800);
PAINT SKYBLUE (-7800 1800);
FORCEPROP 0 LAST $SEC 1
J 0
(-7800 1825);
DISPLAY 0.680851 (-7800 1825);
PAINT MONO (-7800 1825);
DISPLAY INVISIBLE (-7800 1825);
FORCEPROP 0 LAST CDS_SEC 1
J 0
(-7800 1825);
DISPLAY 1.021277 (-7800 1825);
DISPLAY INVISIBLE (-7800 1825);
FORCEPROP 1 LASTPIN (-7850 1800) $PN 1
J 0
(-7840 1780);
DISPLAY 0.489362 (-7840 1780);
PAINT MONO (-7840 1780);
FORCEPROP 1 LASTPIN (-7850 1600) $PN 2
J 0
(-7840 1580);
DISPLAY 0.489362 (-7840 1580);
PAINT MONO (-7840 1580);
FORCEPROP 1 LAST PACK_TYPE 0402
J 0
(-7800 1500);
DISPLAY 0.489362 (-7800 1500);
PAINT SKYBLUE (-7800 1500);
FORCEPROP 1 LAST VOLTAGE 25V
J 0
(-7800 1700);
DISPLAY 0.489362 (-7800 1700);
PAINT SKYBLUE (-7800 1700);
FORCEPROP 1 LAST VALUE 0.1UF
J 0
(-7800 1750);
DISPLAY 0.489362 (-7800 1750);
PAINT SKYBLUE (-7800 1750);
FORCEPROP 1 LAST TOLERANCE 10%
J 0
(-7800 1650);
DISPLAY 0.489362 (-7800 1650);
PAINT SKYBLUE (-7800 1650);
FORCEPROP 1 LAST MATERIAL X7R
J 0
(-7800 1600);
DISPLAY 0.489362 (-7800 1600);
PAINT SKYBLUE (-7800 1600);
FORCEPROP 2 LAST CDS_LIB pure_quanta
J 0
(-7850 1700);
DISPLAY INVISIBLE (-7850 1700);
FORCEPROP 1 LAST PATH I4
J 0
(-7800 1850);
DISPLAY 0.978723 (-7800 1850);
PAINT WHITE (-7800 1850);
DISPLAY INVISIBLE (-7800 1850);
FORCEPROP 1 LAST PART_NUMBER CH4104K1B00
J 0
(-7800 1550);
DISPLAY 0.489362 (-7800 1550);
PAINT SKYBLUE (-7800 1550);
DISPLAY INVISIBLE (-7800 1550);
FORCEADD UNIVERSAL_GND..1
(-7200 5400);
FORCEPROP 3 LASTPIN (-7200 5450) SIG_NAME GND\g
J 0
(-7190 5460);
DISPLAY 0.659574 (-7190 5460);
PAINT MONO (-7190 5460);
DISPLAY INVISIBLE (-7190 5460);
FORCEPROP 2 LAST CDS_LIB pure_quanta_power
J 0
(-7200 5400);
DISPLAY INVISIBLE (-7200 5400);
FORCEPROP 1 LAST HDL_POWER GND
J 1
(-7175 5325);
DISPLAY 0.872340 (-7175 5325);
PAINT GREEN (-7175 5325);
DISPLAY INVISIBLE (-7175 5325);
FORCEPROP 1 LAST PATH I40
J 0
(-7125 5400);
DISPLAY 0.872340 (-7125 5400);
PAINT AQUA (-7125 5400);
DISPLAY INVISIBLE (-7125 5400);
FORCEADD Q_CAP..1
(-7200 5675);
FORCEPROP 1 LAST LOCATION PC321_SOP1_1
J 0
(-7150 5775);
DISPLAY 0.489362 (-7150 5775);
PAINT SKYBLUE (-7150 5775);
FORCEPROP 0 LAST $SEC 1
J 0
(-7150 5825);
DISPLAY 0.680851 (-7150 5825);
PAINT MONO (-7150 5825);
DISPLAY INVISIBLE (-7150 5825);
FORCEPROP 0 LAST CDS_SEC 1
J 0
(-7150 5825);
DISPLAY 1.021277 (-7150 5825);
DISPLAY INVISIBLE (-7150 5825);
FORCEPROP 1 LASTPIN (-7200 5775) $PN 1
J 0
(-7190 5755);
DISPLAY 0.489362 (-7190 5755);
PAINT MONO (-7190 5755);
FORCEPROP 1 LASTPIN (-7200 5575) $PN 2
J 0
(-7190 5555);
DISPLAY 0.489362 (-7190 5555);
PAINT MONO (-7190 5555);
FORCEPROP 1 LAST TOLERANCE 10%
J 0
(-7150 5625);
DISPLAY 0.489362 (-7150 5625);
PAINT SKYBLUE (-7150 5625);
FORCEPROP 1 LAST VOLTAGE 10V
J 0
(-7150 5675);
DISPLAY 0.489362 (-7150 5675);
PAINT SKYBLUE (-7150 5675);
FORCEPROP 1 LAST PACK_TYPE C0402
J 0
(-7150 5475);
DISPLAY 0.489362 (-7150 5475);
PAINT SKYBLUE (-7150 5475);
FORCEPROP 1 LAST VALUE 2.2UF
J 0
(-7150 5725);
DISPLAY 0.489362 (-7150 5725);
PAINT SKYBLUE (-7150 5725);
FORCEPROP 1 LAST MATERIAL X6S
J 0
(-7150 5575);
DISPLAY 0.489362 (-7150 5575);
PAINT SKYBLUE (-7150 5575);
FORCEPROP 2 LAST CDS_LIB pure_quanta
J 0
(-7200 5675);
DISPLAY INVISIBLE (-7200 5675);
FORCEPROP 1 LAST PATH I41
J 0
(-7150 5825);
DISPLAY 0.978723 (-7150 5825);
PAINT WHITE (-7150 5825);
DISPLAY INVISIBLE (-7150 5825);
FORCEPROP 1 LAST PART_NUMBER CH5222KEB01
J 0
(-7150 5525);
DISPLAY 0.489362 (-7150 5525);
PAINT SKYBLUE (-7150 5525);
DISPLAY INVISIBLE (-7150 5525);
FORCEADD VCC_CORE..1
(-7550 6050);
FORCEPROP 3 LASTPIN (-7550 6000) SIG_NAME PVDDCR_CPU0_P1_PVCC\g
J 0
(-7540 6010);
DISPLAY 0.659574 (-7540 6010);
PAINT MONO (-7540 6010);
DISPLAY INVISIBLE (-7540 6010);
FORCEPROP 1 LAST HDL_POWER PVDDCR_CPU0_P1_PVCC
J 1
(-7550 6100);
DISPLAY 0.489362 (-7550 6100);
PAINT GREEN (-7550 6100);
FORCEPROP 2 LAST CDS_LIB pure_quanta_power
J 0
(-7550 6050);
DISPLAY INVISIBLE (-7550 6050);
FORCEPROP 1 LAST PATH I42
J 0
(-7500 6075);
DISPLAY 0.872340 (-7500 6075);
PAINT AQUA (-7500 6075);
DISPLAY INVISIBLE (-7500 6075);
FORCEADD Q_CAP..1
(-5450 5600);
FORCEPROP 1 LAST LOCATION PC325_1
J 0
(-5400 5700);
DISPLAY 0.489362 (-5400 5700);
PAINT SKYBLUE (-5400 5700);
FORCEPROP 0 LAST $SEC 1
J 0
(-5400 5750);
DISPLAY 0.680851 (-5400 5750);
PAINT MONO (-5400 5750);
DISPLAY INVISIBLE (-5400 5750);
FORCEPROP 0 LAST CDS_SEC 1
J 0
(-5400 5750);
DISPLAY 1.021277 (-5400 5750);
DISPLAY INVISIBLE (-5400 5750);
FORCEPROP 1 LASTPIN (-5450 5700) $PN 1
J 0
(-5440 5680);
DISPLAY 0.489362 (-5440 5680);
PAINT MONO (-5440 5680);
FORCEPROP 1 LASTPIN (-5450 5500) $PN 2
J 0
(-5440 5480);
DISPLAY 0.489362 (-5440 5480);
PAINT MONO (-5440 5480);
FORCEPROP 1 LAST MATERIAL X7R
J 0
(-5400 5500);
DISPLAY 0.489362 (-5400 5500);
PAINT SKYBLUE (-5400 5500);
FORCEPROP 1 LAST PACK_TYPE 0402
J 0
(-5400 5400);
DISPLAY 0.489362 (-5400 5400);
PAINT SKYBLUE (-5400 5400);
FORCEPROP 1 LAST VALUE 0.1UF
J 0
(-5400 5650);
DISPLAY 0.489362 (-5400 5650);
PAINT SKYBLUE (-5400 5650);
FORCEPROP 1 LAST VOLTAGE 25V
J 0
(-5400 5600);
DISPLAY 0.489362 (-5400 5600);
PAINT SKYBLUE (-5400 5600);
FORCEPROP 1 LAST TOLERANCE 10%
J 0
(-5400 5550);
DISPLAY 0.489362 (-5400 5550);
PAINT SKYBLUE (-5400 5550);
FORCEPROP 2 LAST CDS_LIB pure_quanta
J 0
(-5450 5600);
DISPLAY INVISIBLE (-5450 5600);
FORCEPROP 1 LAST PATH I43
J 0
(-5400 5750);
DISPLAY 0.978723 (-5400 5750);
PAINT WHITE (-5400 5750);
DISPLAY INVISIBLE (-5400 5750);
FORCEPROP 1 LAST PART_NUMBER CH4104K1B00
J 0
(-5400 5450);
DISPLAY 0.489362 (-5400 5450);
PAINT SKYBLUE (-5400 5450);
DISPLAY INVISIBLE (-5400 5450);
FORCEADD Q_CAP..1
(-5125 5600);
FORCEPROP 1 LAST LOCATION PC323_1
J 0
(-5075 5700);
DISPLAY 0.489362 (-5075 5700);
PAINT SKYBLUE (-5075 5700);
FORCEPROP 0 LAST $SEC 1
J 0
(-5075 5725);
DISPLAY 0.680851 (-5075 5725);
PAINT MONO (-5075 5725);
DISPLAY INVISIBLE (-5075 5725);
FORCEPROP 0 LAST CDS_SEC 1
J 0
(-5075 5725);
DISPLAY 1.021277 (-5075 5725);
DISPLAY INVISIBLE (-5075 5725);
FORCEPROP 1 LASTPIN (-5125 5700) $PN 1
J 0
(-5115 5680);
DISPLAY 0.489362 (-5115 5680);
PAINT MONO (-5115 5680);
FORCEPROP 1 LASTPIN (-5125 5500) $PN 2
J 0
(-5115 5480);
DISPLAY 0.489362 (-5115 5480);
PAINT MONO (-5115 5480);
FORCEPROP 1 LAST PACK_TYPE C0402
J 0
(-5075 5400);
DISPLAY 0.489362 (-5075 5400);
PAINT SKYBLUE (-5075 5400);
FORCEPROP 1 LAST MATERIAL X6S
J 0
(-5075 5500);
DISPLAY 0.489362 (-5075 5500);
PAINT SKYBLUE (-5075 5500);
FORCEPROP 1 LAST TOLERANCE 10%
J 0
(-5075 5550);
DISPLAY 0.489362 (-5075 5550);
PAINT SKYBLUE (-5075 5550);
FORCEPROP 1 LAST VOLTAGE 25V
J 0
(-5075 5600);
DISPLAY 0.489362 (-5075 5600);
PAINT SKYBLUE (-5075 5600);
FORCEPROP 1 LAST VALUE 1UF
J 0
(-5075 5650);
DISPLAY 0.489362 (-5075 5650);
PAINT SKYBLUE (-5075 5650);
FORCEPROP 2 LAST CDS_LIB pure_quanta
J 0
(-5125 5600);
DISPLAY INVISIBLE (-5125 5600);
FORCEPROP 1 LAST PATH I44
J 0
(-5075 5750);
DISPLAY 0.978723 (-5075 5750);
PAINT WHITE (-5075 5750);
DISPLAY INVISIBLE (-5075 5750);
FORCEPROP 1 LAST PART_NUMBER CH5104KEB02
J 0
(-5075 5450);
DISPLAY 0.489362 (-5075 5450);
PAINT SKYBLUE (-5075 5450);
DISPLAY INVISIBLE (-5075 5450);
FORCEADD Q_CAP..1
(-4700 4550);
FORCEPROP 1 LAST LOCATION PC141
J 0
(-4650 4650);
DISPLAY 0.489362 (-4650 4650);
PAINT SKYBLUE (-4650 4650);
FORCEPROP 0 LAST $SEC 1
J 0
(-4650 4700);
DISPLAY 0.680851 (-4650 4700);
PAINT MONO (-4650 4700);
DISPLAY INVISIBLE (-4650 4700);
FORCEPROP 0 LAST CDS_SEC 1
J 0
(-4650 4700);
DISPLAY 1.021277 (-4650 4700);
DISPLAY INVISIBLE (-4650 4700);
FORCEPROP 1 LASTPIN (-4700 4650) $PN 1
J 0
(-4690 4630);
DISPLAY 0.489362 (-4690 4630);
PAINT MONO (-4690 4630);
FORCEPROP 1 LASTPIN (-4700 4450) $PN 2
J 0
(-4690 4430);
DISPLAY 0.489362 (-4690 4430);
PAINT MONO (-4690 4430);
FORCEPROP 1 LAST MATERIAL EMPTY
J 0
(-4650 4450);
DISPLAY 0.489362 (-4650 4450);
PAINT RED (-4650 4450);
FORCEPROP 1 LAST PACK_TYPE C0402
J 0
(-4650 4350);
DISPLAY 0.489362 (-4650 4350);
PAINT SKYBLUE (-4650 4350);
FORCEPROP 1 LAST VOLTAGE 50V
J 0
(-4650 4550);
DISPLAY 0.489362 (-4650 4550);
PAINT SKYBLUE (-4650 4550);
FORCEPROP 1 LAST TOLERANCE 10%
J 0
(-4650 4500);
DISPLAY 0.489362 (-4650 4500);
PAINT SKYBLUE (-4650 4500);
FORCEPROP 1 LAST VALUE 560PF
J 0
(-4650 4600);
DISPLAY 0.489362 (-4650 4600);
PAINT SKYBLUE (-4650 4600);
FORCEPROP 2 LAST CDS_LIB pure_quanta
J 0
(-4700 4550);
DISPLAY INVISIBLE (-4700 4550);
FORCEPROP 1 LAST PATH I45
J 0
(-4650 4700);
DISPLAY 0.978723 (-4650 4700);
PAINT WHITE (-4650 4700);
DISPLAY INVISIBLE (-4650 4700);
FORCEPROP 1 LAST PART_NUMBER CH1566K1B09
J 0
(-4650 4400);
DISPLAY 0.489362 (-4650 4400);
PAINT SKYBLUE (-4650 4400);
DISPLAY INVISIBLE (-4650 4400);
FORCEADD Q_RES..1
(-4800 5100);
FORCEPROP 1 LAST LOCATION PR209
J 0
(-4825 5150);
DISPLAY 0.489362 (-4825 5150);
PAINT SKYBLUE (-4825 5150);
FORCEPROP 0 LAST $SEC 1
J 0
(-4775 5175);
DISPLAY 0.680851 (-4775 5175);
PAINT MONO (-4775 5175);
DISPLAY INVISIBLE (-4775 5175);
FORCEPROP 0 LAST CDS_SEC 1
J 0
(-4775 5175);
DISPLAY 1.021277 (-4775 5175);
DISPLAY INVISIBLE (-4775 5175);
FORCEPROP 1 LASTPIN (-4900 5100) $PN 1
J 0
(-4888 5112);
DISPLAY 0.489362 (-4888 5112);
PAINT MONO (-4888 5112);
FORCEPROP 1 LASTPIN (-4700 5100) $PN 2
J 0
(-4738 5112);
DISPLAY 0.489362 (-4738 5112);
PAINT MONO (-4738 5112);
FORCEPROP 1 LAST WATTAGE 1/16W
J 0
(-4700 5050);
DISPLAY 0.489362 (-4700 5050);
PAINT SKYBLUE (-4700 5050);
FORCEPROP 1 LAST PACK_TYPE 0402LF
J 0
(-4700 5000);
DISPLAY 0.489362 (-4700 5000);
PAINT SKYBLUE (-4700 5000);
FORCEPROP 1 LAST MATERIAL CHIP
J 0
(-5050 5000);
DISPLAY 0.489362 (-5050 5000);
PAINT SKYBLUE (-5050 5000);
FORCEPROP 1 LAST TOLERANCE 1%
J 0
(-4700 5125);
DISPLAY 0.489362 (-4700 5125);
PAINT SKYBLUE (-4700 5125);
FORCEPROP 1 LAST VALUE 5.6
J 2
(-4900 5125);
DISPLAY 0.489362 (-4900 5125);
PAINT SKYBLUE (-4900 5125);
FORCEPROP 2 LAST CDS_LIB pure_quanta
J 0
(-4800 5100);
DISPLAY INVISIBLE (-4800 5100);
FORCEPROP 1 LAST PATH I46
J 0
(-4850 5250);
DISPLAY 0.978723 (-4850 5250);
PAINT WHITE (-4850 5250);
DISPLAY INVISIBLE (-4850 5250);
FORCEPROP 1 LAST PART_NUMBER CS-5602FB01
J 0
(-5050 5050);
DISPLAY 0.489362 (-5050 5050);
PAINT SKYBLUE (-5050 5050);
DISPLAY INVISIBLE (-5050 5050);
FORCEADD OFFPAGE..3
R 2
(-4150 4500);
FORCEPROP 2 LAST $XR0 215 
J 0
(-4430 4500);
DISPLAY 0.638298 (-4430 4500);
PAINT MONO (-4430 4500);
FORCEPROP 2 LAST CDS_LIB standard
J 2
(-4150 4500);
DISPLAY INVISIBLE (-4150 4500);
FORCEPROP 1 LAST OFFPAGE TRUE
J 2
(-4475 4375);
DISPLAY 0.872340 (-4475 4375);
PAINT GREEN (-4475 4375);
DISPLAY INVISIBLE (-4475 4375);
FORCEPROP 1 LAST COMMENT_BODY TRUE
J 2
(-4100 4400);
DISPLAY 0.872340 (-4100 4400);
PAINT GREEN (-4100 4400);
DISPLAY INVISIBLE (-4100 4400);
FORCEPROP 2 LAST PATH I47
J 0
(-4425 4550);
DISPLAY 0.680851 (-4425 4550);
DISPLAY INVISIBLE (-4425 4550);
FORCEADD Q_CAP..1
(-4800 5600);
FORCEPROP 1 LAST LOCATION PC327_1
J 0
(-4750 5700);
DISPLAY 0.489362 (-4750 5700);
PAINT SKYBLUE (-4750 5700);
FORCEPROP 0 LAST $SEC 1
J 0
(-4750 5725);
DISPLAY 0.680851 (-4750 5725);
PAINT MONO (-4750 5725);
DISPLAY INVISIBLE (-4750 5725);
FORCEPROP 0 LAST CDS_SEC 1
J 0
(-4750 5725);
DISPLAY 1.021277 (-4750 5725);
DISPLAY INVISIBLE (-4750 5725);
FORCEPROP 1 LASTPIN (-4800 5700) $PN 1
J 0
(-4790 5680);
DISPLAY 0.489362 (-4790 5680);
PAINT MONO (-4790 5680);
FORCEPROP 1 LASTPIN (-4800 5500) $PN 2
J 0
(-4790 5480);
DISPLAY 0.489362 (-4790 5480);
PAINT MONO (-4790 5480);
FORCEPROP 1 LAST PACK_TYPE C0805
J 0
(-4750 5400);
DISPLAY 0.489362 (-4750 5400);
PAINT SKYBLUE (-4750 5400);
FORCEPROP 1 LAST VALUE 22UF
J 0
(-4750 5650);
DISPLAY 0.489362 (-4750 5650);
PAINT SKYBLUE (-4750 5650);
FORCEPROP 1 LAST VOLTAGE 16V
J 0
(-4750 5600);
DISPLAY 0.489362 (-4750 5600);
PAINT SKYBLUE (-4750 5600);
FORCEPROP 1 LAST MATERIAL X6S
J 0
(-4750 5500);
DISPLAY 0.489362 (-4750 5500);
PAINT SKYBLUE (-4750 5500);
FORCEPROP 1 LAST TOLERANCE 20%
J 0
(-4750 5550);
DISPLAY 0.489362 (-4750 5550);
PAINT SKYBLUE (-4750 5550);
FORCEPROP 2 LAST CDS_LIB pure_quanta
J 0
(-4800 5600);
DISPLAY INVISIBLE (-4800 5600);
FORCEPROP 1 LAST PATH I48
J 0
(-4750 5750);
DISPLAY 0.978723 (-4750 5750);
PAINT WHITE (-4750 5750);
DISPLAY INVISIBLE (-4750 5750);
FORCEPROP 1 LAST PART_NUMBER CH6223MEA01
J 0
(-4750 5450);
DISPLAY 0.489362 (-4750 5450);
PAINT SKYBLUE (-4750 5450);
DISPLAY INVISIBLE (-4750 5450);
FORCEADD Q_CAP..1
(-4475 5600);
FORCEPROP 1 LAST LOCATION PC329_1
J 0
(-4425 5700);
DISPLAY 0.489362 (-4425 5700);
PAINT SKYBLUE (-4425 5700);
FORCEPROP 0 LAST $SEC 1
J 0
(-4425 5725);
DISPLAY 0.680851 (-4425 5725);
PAINT MONO (-4425 5725);
DISPLAY INVISIBLE (-4425 5725);
FORCEPROP 0 LAST CDS_SEC 1
J 0
(-4425 5725);
DISPLAY 1.021277 (-4425 5725);
DISPLAY INVISIBLE (-4425 5725);
FORCEPROP 1 LASTPIN (-4475 5700) $PN 1
J 0
(-4465 5680);
DISPLAY 0.489362 (-4465 5680);
PAINT MONO (-4465 5680);
FORCEPROP 1 LASTPIN (-4475 5500) $PN 2
J 0
(-4465 5480);
DISPLAY 0.489362 (-4465 5480);
PAINT MONO (-4465 5480);
FORCEPROP 1 LAST TOLERANCE 20%
J 0
(-4425 5550);
DISPLAY 0.489362 (-4425 5550);
PAINT SKYBLUE (-4425 5550);
FORCEPROP 1 LAST VOLTAGE 16V
J 0
(-4425 5600);
DISPLAY 0.489362 (-4425 5600);
PAINT SKYBLUE (-4425 5600);
FORCEPROP 1 LAST PACK_TYPE C0805
J 0
(-4425 5400);
DISPLAY 0.489362 (-4425 5400);
PAINT SKYBLUE (-4425 5400);
FORCEPROP 1 LAST MATERIAL X6S
J 0
(-4425 5500);
DISPLAY 0.489362 (-4425 5500);
PAINT SKYBLUE (-4425 5500);
FORCEPROP 1 LAST VALUE 22UF
J 0
(-4425 5650);
DISPLAY 0.489362 (-4425 5650);
PAINT SKYBLUE (-4425 5650);
FORCEPROP 2 LAST CDS_LIB pure_quanta
J 0
(-4475 5600);
DISPLAY INVISIBLE (-4475 5600);
FORCEPROP 1 LAST PATH I49
J 0
(-4425 5750);
DISPLAY 0.978723 (-4425 5750);
PAINT WHITE (-4425 5750);
DISPLAY INVISIBLE (-4425 5750);
FORCEPROP 1 LAST PART_NUMBER CH6223MEA01
J 0
(-4425 5450);
DISPLAY 0.489362 (-4425 5450);
PAINT SKYBLUE (-4425 5450);
DISPLAY INVISIBLE (-4425 5450);
FORCEADD UNIVERSAL_GND..1
(-7525 1500);
FORCEPROP 3 LASTPIN (-7525 1550) SIG_NAME GND\g
J 0
(-7515 1560);
DISPLAY 0.659574 (-7515 1560);
PAINT MONO (-7515 1560);
DISPLAY INVISIBLE (-7515 1560);
FORCEPROP 2 LAST CDS_LIB pure_quanta_power
J 0
(-7525 1500);
DISPLAY INVISIBLE (-7525 1500);
FORCEPROP 1 LAST HDL_POWER GND
J 1
(-7500 1425);
DISPLAY 0.872340 (-7500 1425);
PAINT GREEN (-7500 1425);
DISPLAY INVISIBLE (-7500 1425);
FORCEPROP 1 LAST PATH I5
J 0
(-7450 1500);
DISPLAY 0.872340 (-7450 1500);
PAINT AQUA (-7450 1500);
DISPLAY INVISIBLE (-7450 1500);
FORCEADD Q_CAP..1
(-4175 5600);
FORCEPROP 1 LAST LOCATION PC331_1
J 0
(-4125 5700);
DISPLAY 0.489362 (-4125 5700);
PAINT SKYBLUE (-4125 5700);
FORCEPROP 0 LAST $SEC 1
J 0
(-4125 5725);
DISPLAY 0.680851 (-4125 5725);
PAINT MONO (-4125 5725);
DISPLAY INVISIBLE (-4125 5725);
FORCEPROP 0 LAST CDS_SEC 1
J 0
(-4125 5725);
DISPLAY 1.021277 (-4125 5725);
DISPLAY INVISIBLE (-4125 5725);
FORCEPROP 1 LASTPIN (-4175 5700) $PN 1
J 0
(-4165 5680);
DISPLAY 0.489362 (-4165 5680);
PAINT MONO (-4165 5680);
FORCEPROP 1 LASTPIN (-4175 5500) $PN 2
J 0
(-4165 5480);
DISPLAY 0.489362 (-4165 5480);
PAINT MONO (-4165 5480);
FORCEPROP 1 LAST VALUE 22UF
J 0
(-4125 5650);
DISPLAY 0.489362 (-4125 5650);
PAINT SKYBLUE (-4125 5650);
FORCEPROP 1 LAST PACK_TYPE C0805
J 0
(-4125 5400);
DISPLAY 0.489362 (-4125 5400);
PAINT SKYBLUE (-4125 5400);
FORCEPROP 1 LAST VOLTAGE 16V
J 0
(-4125 5600);
DISPLAY 0.489362 (-4125 5600);
PAINT SKYBLUE (-4125 5600);
FORCEPROP 1 LAST TOLERANCE 20%
J 0
(-4125 5550);
DISPLAY 0.489362 (-4125 5550);
PAINT SKYBLUE (-4125 5550);
FORCEPROP 1 LAST MATERIAL X6S
J 0
(-4125 5500);
DISPLAY 0.489362 (-4125 5500);
PAINT SKYBLUE (-4125 5500);
FORCEPROP 2 LAST CDS_LIB pure_quanta
J 0
(-4175 5600);
DISPLAY INVISIBLE (-4175 5600);
FORCEPROP 1 LAST PATH I50
J 0
(-4125 5750);
DISPLAY 0.978723 (-4125 5750);
PAINT WHITE (-4125 5750);
DISPLAY INVISIBLE (-4125 5750);
FORCEPROP 1 LAST PART_NUMBER CH6223MEA01
J 0
(-4125 5450);
DISPLAY 0.489362 (-4125 5450);
PAINT SKYBLUE (-4125 5450);
DISPLAY INVISIBLE (-4125 5450);
FORCEADD OFFPAGE..3
R 2
(-3925 1725);
FORCEPROP 2 LAST $XR0 216 
J 0
(-4205 1725);
DISPLAY 0.638298 (-4205 1725);
PAINT MONO (-4205 1725);
FORCEPROP 2 LAST CDS_LIB standard
J 2
(-3925 1725);
DISPLAY INVISIBLE (-3925 1725);
FORCEPROP 1 LAST OFFPAGE TRUE
J 2
(-4250 1600);
DISPLAY 0.872340 (-4250 1600);
PAINT GREEN (-4250 1600);
DISPLAY INVISIBLE (-4250 1600);
FORCEPROP 1 LAST COMMENT_BODY TRUE
J 2
(-3875 1625);
DISPLAY 0.872340 (-3875 1625);
PAINT GREEN (-3875 1625);
DISPLAY INVISIBLE (-3875 1625);
FORCEPROP 2 LAST PATH I51
J 0
(-4200 1775);
DISPLAY 0.680851 (-4200 1775);
DISPLAY INVISIBLE (-4200 1775);
FORCEADD Q_INDUCTOR4P_14..1
(-2950 1850);
FORCEPROP 1 LAST LOCATION PL36
J 0
(-3175 2105);
DISPLAY 0.489362 (-3175 2105);
PAINT SKYBLUE (-3175 2105);
FORCEPROP 0 LAST $SEC 1
J 0
(-3175 2250);
DISPLAY 0.680851 (-3175 2250);
PAINT MONO (-3175 2250);
DISPLAY INVISIBLE (-3175 2250);
FORCEPROP 0 LAST CDS_SEC 1
J 0
(-3175 2250);
DISPLAY 1.021277 (-3175 2250);
DISPLAY INVISIBLE (-3175 2250);
FORCEPROP 0 LASTPIN (-3350 1975) $PN 1
J 2
(-3360 1985);
DISPLAY 0.489362 (-3360 1985);
PAINT MONO (-3360 1985);
FORCEPROP 0 LASTPIN (-3350 1725) $PN 2
J 2
(-3360 1735);
DISPLAY 0.489362 (-3360 1735);
PAINT MONO (-3360 1735);
FORCEPROP 0 LASTPIN (-2550 1725) $PN 3
J 0
(-2540 1735);
DISPLAY 0.489362 (-2540 1735);
PAINT MONO (-2540 1735);
FORCEPROP 0 LASTPIN (-2550 1975) $PN 4
J 0
(-2540 1985);
DISPLAY 0.489362 (-2540 1985);
PAINT MONO (-2540 1985);
FORCEPROP 1 LAST MATERIAL IND
J 0
(-3175 2060);
DISPLAY 0.489362 (-3175 2060);
PAINT SKYBLUE (-3175 2060);
FORCEPROP 2 LAST PART_TYPE SMLF
J 0
(-3175 2200);
DISPLAY 1.021277 (-3175 2200);
FORCEPROP 2 LAST VALUE 150NH
J 0
(-3175 2150);
DISPLAY 0.489362 (-3175 2150);
PAINT SKYBLUE (-3175 2150);
FORCEPROP 1 LAST NEEDS_NO_SIZE TRUE
J 0
(-2950 1850);
DISPLAY 0.468085 (-2950 1850);
PAINT GREEN (-2950 1850);
DISPLAY INVISIBLE (-2950 1850);
FORCEPROP 2 LAST CDS_LIB pure_quanta
J 0
(-2950 1850);
DISPLAY INVISIBLE (-2950 1850);
FORCEPROP 1 LAST PATH I52
J 0
(-2750 2005);
DISPLAY 0.723404 (-2750 2005);
PAINT GREEN (-2750 2005);
DISPLAY INVISIBLE (-2750 2005);
FORCEPROP 1 LAST PART_NUMBER CV+15^0TZ04
J 0
(-3175 2010);
DISPLAY 0.489362 (-3175 2010);
PAINT SKYBLUE (-3175 2010);
DISPLAY INVISIBLE (-3175 2010);
FORCEADD OFFPAGE..3
(-2100 1725);
FORCEPROP 2 LAST $XR0 215 
J 0
(-1886 1725);
DISPLAY 0.638298 (-1886 1725);
PAINT MONO (-1886 1725);
FORCEPROP 2 LAST CDS_LIB standard
J 0
(-2100 1725);
DISPLAY INVISIBLE (-2100 1725);
FORCEPROP 1 LAST OFFPAGE TRUE
J 0
(-1775 1600);
DISPLAY 0.872340 (-1775 1600);
PAINT GREEN (-1775 1600);
DISPLAY INVISIBLE (-1775 1600);
FORCEPROP 1 LAST COMMENT_BODY TRUE
J 0
(-2150 1625);
DISPLAY 0.872340 (-2150 1625);
PAINT GREEN (-2150 1625);
DISPLAY INVISIBLE (-2150 1625);
FORCEPROP 2 LAST PATH I53
J 0
(-1875 1775);
DISPLAY 0.680851 (-1875 1775);
DISPLAY INVISIBLE (-1875 1775);
FORCEADD Q_CAP..1
(-3825 2200);
FORCEPROP 1 LAST LOCATION PC334
J 0
(-3775 2325);
DISPLAY 0.489362 (-3775 2325);
PAINT SKYBLUE (-3775 2325);
FORCEPROP 0 LAST $SEC 1
J 0
(-3775 2350);
DISPLAY 0.680851 (-3775 2350);
PAINT MONO (-3775 2350);
DISPLAY INVISIBLE (-3775 2350);
FORCEPROP 0 LAST CDS_SEC 1
J 0
(-3775 2350);
DISPLAY 1.021277 (-3775 2350);
DISPLAY INVISIBLE (-3775 2350);
FORCEPROP 1 LASTPIN (-3825 2300) $PN 1
J 0
(-3815 2280);
DISPLAY 0.489362 (-3815 2280);
PAINT MONO (-3815 2280);
FORCEPROP 1 LASTPIN (-3825 2100) $PN 2
J 0
(-3815 2080);
DISPLAY 0.489362 (-3815 2080);
PAINT MONO (-3815 2080);
FORCEPROP 1 LAST TOLERANCE 10%
J 0
(-3775 2175);
DISPLAY 0.489362 (-3775 2175);
PAINT SKYBLUE (-3775 2175);
FORCEPROP 1 LAST VALUE 0.22UF
J 0
(-3775 2275);
DISPLAY 0.489362 (-3775 2275);
PAINT SKYBLUE (-3775 2275);
FORCEPROP 1 LAST PACK_TYPE 0402
J 0
(-3775 2025);
DISPLAY 0.489362 (-3775 2025);
PAINT SKYBLUE (-3775 2025);
FORCEPROP 1 LAST VOLTAGE 16V
J 0
(-3775 2225);
DISPLAY 0.489362 (-3775 2225);
PAINT SKYBLUE (-3775 2225);
FORCEPROP 1 LAST MATERIAL X7R
J 0
(-3775 2125);
DISPLAY 0.489362 (-3775 2125);
PAINT SKYBLUE (-3775 2125);
FORCEPROP 2 LAST CDS_LIB pure_quanta
J 0
(-3825 2200);
DISPLAY INVISIBLE (-3825 2200);
FORCEPROP 1 LAST PATH I54
J 0
(-3775 2350);
DISPLAY 0.978723 (-3775 2350);
PAINT WHITE (-3775 2350);
DISPLAY INVISIBLE (-3775 2350);
FORCEPROP 1 LAST PART_NUMBER CH4223K1B00
J 0
(-3775 2075);
DISPLAY 0.489362 (-3775 2075);
PAINT SKYBLUE (-3775 2075);
DISPLAY INVISIBLE (-3775 2075);
FORCEADD UNIVERSAL_GND..1
(-3725 2550);
FORCEPROP 3 LASTPIN (-3725 2600) SIG_NAME GND\g
J 0
(-3715 2610);
DISPLAY 0.659574 (-3715 2610);
PAINT MONO (-3715 2610);
DISPLAY INVISIBLE (-3715 2610);
FORCEPROP 2 LAST CDS_LIB pure_quanta_power
J 0
(-3725 2550);
DISPLAY INVISIBLE (-3725 2550);
FORCEPROP 1 LAST HDL_POWER GND
J 1
(-3700 2475);
DISPLAY 0.872340 (-3700 2475);
PAINT GREEN (-3700 2475);
DISPLAY INVISIBLE (-3700 2475);
FORCEPROP 1 LAST PATH I55
J 0
(-3650 2550);
DISPLAY 0.872340 (-3650 2550);
PAINT AQUA (-3650 2550);
DISPLAY INVISIBLE (-3650 2550);
FORCEADD Q_CAP..1
(-4050 2875);
FORCEPROP 1 LAST LOCATION PC332_2
J 0
(-4000 2975);
DISPLAY 0.489362 (-4000 2975);
PAINT SKYBLUE (-4000 2975);
FORCEPROP 0 LAST $SEC 1
J 0
(-4000 3000);
DISPLAY 0.680851 (-4000 3000);
PAINT MONO (-4000 3000);
DISPLAY INVISIBLE (-4000 3000);
FORCEPROP 0 LAST CDS_SEC 1
J 0
(-4000 3000);
DISPLAY 1.021277 (-4000 3000);
DISPLAY INVISIBLE (-4000 3000);
FORCEPROP 1 LASTPIN (-4050 2975) $PN 1
J 0
(-4040 2955);
DISPLAY 0.489362 (-4040 2955);
PAINT MONO (-4040 2955);
FORCEPROP 1 LASTPIN (-4050 2775) $PN 2
J 0
(-4040 2755);
DISPLAY 0.489362 (-4040 2755);
PAINT MONO (-4040 2755);
FORCEPROP 1 LAST TOLERANCE 20%
J 0
(-4000 2825);
DISPLAY 0.489362 (-4000 2825);
PAINT SKYBLUE (-4000 2825);
FORCEPROP 1 LAST VOLTAGE 16V
J 0
(-4000 2875);
DISPLAY 0.489362 (-4000 2875);
PAINT SKYBLUE (-4000 2875);
FORCEPROP 1 LAST VALUE 22UF
J 0
(-4000 2925);
DISPLAY 0.489362 (-4000 2925);
PAINT SKYBLUE (-4000 2925);
FORCEPROP 1 LAST MATERIAL X6S
J 0
(-4000 2775);
DISPLAY 0.489362 (-4000 2775);
PAINT SKYBLUE (-4000 2775);
FORCEPROP 1 LAST PACK_TYPE C0805
J 0
(-4000 2675);
DISPLAY 0.489362 (-4000 2675);
PAINT SKYBLUE (-4000 2675);
FORCEPROP 2 LAST CDS_LIB pure_quanta
J 0
(-4050 2875);
DISPLAY INVISIBLE (-4050 2875);
FORCEPROP 1 LAST PATH I56
J 0
(-4000 3025);
DISPLAY 0.978723 (-4000 3025);
PAINT WHITE (-4000 3025);
DISPLAY INVISIBLE (-4000 3025);
FORCEPROP 1 LAST PART_NUMBER CH6223MEA01
J 0
(-4000 2725);
DISPLAY 0.489362 (-4000 2725);
PAINT SKYBLUE (-4000 2725);
DISPLAY INVISIBLE (-4000 2725);
FORCEADD Q_CAP..1
(-3725 2875);
FORCEPROP 1 LAST LOCATION PC335_2
J 0
(-3675 2975);
DISPLAY 0.489362 (-3675 2975);
PAINT SKYBLUE (-3675 2975);
FORCEPROP 0 LAST $SEC 1
J 0
(-3675 3000);
DISPLAY 0.680851 (-3675 3000);
PAINT MONO (-3675 3000);
DISPLAY INVISIBLE (-3675 3000);
FORCEPROP 0 LAST CDS_SEC 1
J 0
(-3675 3000);
DISPLAY 0.680851 (-3675 3000);
DISPLAY INVISIBLE (-3675 3000);
FORCEPROP 1 LASTPIN (-3725 2975) $PN 1
J 0
(-3715 2955);
DISPLAY 0.787234 (-3715 2955);
PAINT MONO (-3715 2955);
DISPLAY INVISIBLE (-3715 2955);
FORCEPROP 1 LASTPIN (-3725 2775) $PN 2
J 0
(-3715 2755);
DISPLAY 0.787234 (-3715 2755);
PAINT MONO (-3715 2755);
DISPLAY INVISIBLE (-3715 2755);
FORCEPROP 1 LAST VOLTAGE 16V
J 0
(-3675 2875);
DISPLAY 0.489362 (-3675 2875);
PAINT SKYBLUE (-3675 2875);
FORCEPROP 1 LAST TOLERANCE 20%
J 0
(-3675 2825);
DISPLAY 0.489362 (-3675 2825);
PAINT SKYBLUE (-3675 2825);
FORCEPROP 1 LAST MATERIAL X6S
J 0
(-3675 2775);
DISPLAY 0.489362 (-3675 2775);
PAINT SKYBLUE (-3675 2775);
FORCEPROP 1 LAST PACK_TYPE C0805
J 0
(-3675 2675);
DISPLAY 0.489362 (-3675 2675);
PAINT SKYBLUE (-3675 2675);
FORCEPROP 1 LAST VALUE 22UF
J 0
(-3675 2925);
DISPLAY 0.489362 (-3675 2925);
PAINT SKYBLUE (-3675 2925);
FORCEPROP 2 LAST CDS_LIB pure_quanta
J 0
(-3725 2875);
DISPLAY INVISIBLE (-3725 2875);
FORCEPROP 1 LAST PATH I57
J 0
(-3675 3025);
DISPLAY 0.978723 (-3675 3025);
PAINT WHITE (-3675 3025);
DISPLAY INVISIBLE (-3675 3025);
FORCEPROP 1 LAST PART_NUMBER CH6223MEA01
J 0
(-3675 2725);
DISPLAY 0.489362 (-3675 2725);
PAINT SKYBLUE (-3675 2725);
DISPLAY INVISIBLE (-3675 2725);
FORCEADD VCC_CORE..1
(-3725 3175);
FORCEPROP 3 LASTPIN (-3725 3125) SIG_NAME SW_P12V_AUX_PVDDCR_SOC_P1_FLT\g
J 0
(-3715 3135);
DISPLAY 0.659574 (-3715 3135);
PAINT MONO (-3715 3135);
DISPLAY INVISIBLE (-3715 3135);
FORCEPROP 1 LAST HDL_POWER SW_P12V_AUX_PVDDCR_SOC_P1_FLT
J 1
(-3725 3225);
DISPLAY 0.489362 (-3725 3225);
PAINT GREEN (-3725 3225);
FORCEPROP 2 LAST CDS_LIB pure_quanta_power
J 0
(-3725 3175);
DISPLAY INVISIBLE (-3725 3175);
FORCEPROP 1 LAST PATH I58
J 0
(-3675 3200);
DISPLAY 0.872340 (-3675 3200);
PAINT AQUA (-3675 3200);
DISPLAY INVISIBLE (-3675 3200);
FORCEADD Q_CAPP..1
(-2125 3075);
FORCEPROP 1 LAST LOCATION PC337
J 0
(-2075 3175);
DISPLAY 0.489362 (-2075 3175);
PAINT SKYBLUE (-2075 3175);
FORCEPROP 0 LAST $SEC 1
J 0
(-2075 3200);
DISPLAY 0.680851 (-2075 3200);
PAINT MONO (-2075 3200);
DISPLAY INVISIBLE (-2075 3200);
FORCEPROP 0 LAST CDS_SEC 1
J 0
(-2075 3200);
DISPLAY 1.021277 (-2075 3200);
DISPLAY INVISIBLE (-2075 3200);
FORCEPROP 1 LASTPIN (-2125 3175) $PN 1
J 0
(-2115 3160);
DISPLAY 0.489362 (-2115 3160);
PAINT MONO (-2115 3160);
FORCEPROP 1 LASTPIN (-2125 2975) $PN 2
J 0
(-2115 2960);
DISPLAY 0.489362 (-2115 2960);
PAINT MONO (-2115 2960);
FORCEPROP 1 LAST VOLTAGE 2.5V
J 0
(-2075 3025);
DISPLAY 0.489362 (-2075 3025);
PAINT SKYBLUE (-2075 3025);
FORCEPROP 1 LAST VALUE 470UF
J 0
(-2075 3125);
DISPLAY 0.489362 (-2075 3125);
PAINT SKYBLUE (-2075 3125);
FORCEPROP 1 LAST TOLERANCE 20%
J 0
(-2075 3075);
DISPLAY 0.489362 (-2075 3075);
PAINT SKYBLUE (-2075 3075);
FORCEPROP 1 LAST MATERIAL SPCAP
J 0
(-2075 2975);
DISPLAY 0.489362 (-2075 2975);
PAINT SKYBLUE (-2075 2975);
FORCEPROP 1 LAST PACK_TYPE SMLF
J 0
(-2075 2925);
DISPLAY 0.489362 (-2075 2925);
PAINT SKYBLUE (-2075 2925);
FORCEPROP 2 LAST CDS_LIB pure_quanta
J 0
(-2125 3075);
DISPLAY INVISIBLE (-2125 3075);
FORCEPROP 1 LAST PATH I59
J 0
(-2075 3225);
DISPLAY 0.978723 (-2075 3225);
DISPLAY INVISIBLE (-2075 3225);
FORCEPROP 1 LAST PART_NUMBER CH747LM8825
J 0
(-2075 2875);
DISPLAY 0.489362 (-2075 2875);
PAINT SKYBLUE (-2075 2875);
DISPLAY INVISIBLE (-2075 2875);
FORCEADD OFFPAGE..2
R 2
(-7150 1475);
FORCEPROP 2 LAST $XR2 210 
J 0
(-7555 1439);
DISPLAY 0.638298 (-7555 1439);
PAINT MONO (-7555 1439);
FORCEPROP 2 LAST $XR1 216 
J 0
(-7435 1439);
DISPLAY 0.638298 (-7435 1439);
PAINT MONO (-7435 1439);
FORCEPROP 2 LAST $XR0 215 
J 0
(-7435 1475);
DISPLAY 0.638298 (-7435 1475);
PAINT MONO (-7435 1475);
FORCEPROP 2 LAST CDS_LIB standard
J 0
(-7150 1475);
DISPLAY INVISIBLE (-7150 1475);
FORCEPROP 1 LAST OFFPAGE TRUE
J 2
(-7475 1350);
DISPLAY 0.872340 (-7475 1350);
PAINT GREEN (-7475 1350);
DISPLAY INVISIBLE (-7475 1350);
FORCEPROP 1 LAST COMMENT_BODY TRUE
J 2
(-7105 1380);
DISPLAY 0.872340 (-7105 1380);
PAINT GREEN (-7105 1380);
DISPLAY INVISIBLE (-7105 1380);
FORCEPROP 2 LAST PATH I6
J 0
(-7400 1525);
DISPLAY 0.680851 (-7400 1525);
DISPLAY INVISIBLE (-7400 1525);
FORCEADD Q_CAP..1
(-1700 1800);
FORCEPROP 1 LAST LOCATION PC339_2
J 0
(-1650 1900);
DISPLAY 0.489362 (-1650 1900);
PAINT SKYBLUE (-1650 1900);
FORCEPROP 0 LAST $SEC 1
J 0
(-1650 1925);
DISPLAY 0.680851 (-1650 1925);
PAINT MONO (-1650 1925);
DISPLAY INVISIBLE (-1650 1925);
FORCEPROP 0 LAST CDS_SEC 1
J 0
(-1650 1925);
DISPLAY 1.021277 (-1650 1925);
DISPLAY INVISIBLE (-1650 1925);
FORCEPROP 1 LASTPIN (-1700 1900) $PN 1
J 0
(-1690 1880);
DISPLAY 0.489362 (-1690 1880);
PAINT MONO (-1690 1880);
FORCEPROP 1 LASTPIN (-1700 1700) $PN 2
J 0
(-1690 1680);
DISPLAY 0.489362 (-1690 1680);
PAINT MONO (-1690 1680);
FORCEPROP 1 LAST PACK_TYPE C0805
J 0
(-1650 1600);
DISPLAY 0.489362 (-1650 1600);
PAINT SKYBLUE (-1650 1600);
FORCEPROP 1 LAST MATERIAL X6S
J 0
(-1650 1700);
DISPLAY 0.489362 (-1650 1700);
PAINT SKYBLUE (-1650 1700);
FORCEPROP 1 LAST TOLERANCE 20%
J 0
(-1650 1750);
DISPLAY 0.489362 (-1650 1750);
PAINT SKYBLUE (-1650 1750);
FORCEPROP 1 LAST VALUE 22UF
J 0
(-1650 1850);
DISPLAY 0.489362 (-1650 1850);
PAINT SKYBLUE (-1650 1850);
FORCEPROP 1 LAST VOLTAGE 4V
J 0
(-1650 1800);
DISPLAY 0.489362 (-1650 1800);
PAINT SKYBLUE (-1650 1800);
FORCEPROP 2 LAST CDS_LIB pure_quanta
J 0
(-1700 1800);
DISPLAY INVISIBLE (-1700 1800);
FORCEPROP 1 LAST PATH I60
J 0
(-1650 1950);
DISPLAY 0.978723 (-1650 1950);
PAINT WHITE (-1650 1950);
DISPLAY INVISIBLE (-1650 1950);
FORCEPROP 1 LAST PART_NUMBER CH622KMEA03
J 0
(-1650 1650);
DISPLAY 0.489362 (-1650 1650);
PAINT SKYBLUE (-1650 1650);
DISPLAY INVISIBLE (-1650 1650);
FORCEADD UNIVERSAL_GND..1
(-1275 1450);
FORCEPROP 3 LASTPIN (-1275 1500) SIG_NAME GND\g
J 0
(-1265 1510);
DISPLAY 0.659574 (-1265 1510);
PAINT MONO (-1265 1510);
DISPLAY INVISIBLE (-1265 1510);
FORCEPROP 2 LAST CDS_LIB pure_quanta_power
J 0
(-1275 1450);
DISPLAY INVISIBLE (-1275 1450);
FORCEPROP 1 LAST HDL_POWER GND
J 1
(-1250 1375);
DISPLAY 0.872340 (-1250 1375);
PAINT GREEN (-1250 1375);
DISPLAY INVISIBLE (-1250 1375);
FORCEPROP 1 LAST PATH I61
J 0
(-1200 1450);
DISPLAY 0.872340 (-1200 1450);
PAINT AQUA (-1200 1450);
DISPLAY INVISIBLE (-1200 1450);
FORCEADD Q_CAP..1
(-1275 1800);
FORCEPROP 1 LAST LOCATION PC342_2
J 0
(-1225 1900);
DISPLAY 0.489362 (-1225 1900);
PAINT SKYBLUE (-1225 1900);
FORCEPROP 0 LAST $SEC 1
J 0
(-1225 1925);
DISPLAY 0.680851 (-1225 1925);
PAINT MONO (-1225 1925);
DISPLAY INVISIBLE (-1225 1925);
FORCEPROP 0 LAST CDS_SEC 1
J 0
(-1225 1925);
DISPLAY 1.021277 (-1225 1925);
DISPLAY INVISIBLE (-1225 1925);
FORCEPROP 1 LASTPIN (-1275 1900) $PN 1
J 0
(-1265 1880);
DISPLAY 0.489362 (-1265 1880);
PAINT MONO (-1265 1880);
FORCEPROP 1 LASTPIN (-1275 1700) $PN 2
J 0
(-1265 1680);
DISPLAY 0.489362 (-1265 1680);
PAINT MONO (-1265 1680);
FORCEPROP 1 LAST PACK_TYPE C0805
J 0
(-1225 1600);
DISPLAY 0.489362 (-1225 1600);
PAINT SKYBLUE (-1225 1600);
FORCEPROP 1 LAST MATERIAL X6S
J 0
(-1225 1700);
DISPLAY 0.489362 (-1225 1700);
PAINT SKYBLUE (-1225 1700);
FORCEPROP 1 LAST TOLERANCE 20%
J 0
(-1225 1750);
DISPLAY 0.489362 (-1225 1750);
PAINT SKYBLUE (-1225 1750);
FORCEPROP 1 LAST VALUE 22UF
J 0
(-1225 1850);
DISPLAY 0.489362 (-1225 1850);
PAINT SKYBLUE (-1225 1850);
FORCEPROP 1 LAST VOLTAGE 4V
J 0
(-1225 1800);
DISPLAY 0.489362 (-1225 1800);
PAINT SKYBLUE (-1225 1800);
FORCEPROP 2 LAST CDS_LIB pure_quanta
J 0
(-1275 1800);
DISPLAY INVISIBLE (-1275 1800);
FORCEPROP 1 LAST PATH I62
J 0
(-1225 1950);
DISPLAY 0.978723 (-1225 1950);
PAINT WHITE (-1225 1950);
DISPLAY INVISIBLE (-1225 1950);
FORCEPROP 1 LAST PART_NUMBER CH622KMEA03
J 0
(-1225 1650);
DISPLAY 0.489362 (-1225 1650);
PAINT SKYBLUE (-1225 1650);
DISPLAY INVISIBLE (-1225 1650);
FORCEADD Q_CAPP..1
(-1775 3075);
FORCEPROP 1 LAST LOCATION PC340
J 0
(-1725 3175);
DISPLAY 0.489362 (-1725 3175);
PAINT SKYBLUE (-1725 3175);
FORCEPROP 0 LAST $SEC 1
J 0
(-1725 3200);
DISPLAY 0.680851 (-1725 3200);
PAINT MONO (-1725 3200);
DISPLAY INVISIBLE (-1725 3200);
FORCEPROP 0 LAST CDS_SEC 1
J 0
(-1725 3200);
DISPLAY 1.021277 (-1725 3200);
DISPLAY INVISIBLE (-1725 3200);
FORCEPROP 1 LASTPIN (-1775 3175) $PN 1
J 0
(-1765 3160);
DISPLAY 0.489362 (-1765 3160);
PAINT MONO (-1765 3160);
FORCEPROP 1 LASTPIN (-1775 2975) $PN 2
J 0
(-1765 2960);
DISPLAY 0.489362 (-1765 2960);
PAINT MONO (-1765 2960);
FORCEPROP 1 LAST PACK_TYPE SMLF
J 0
(-1725 2925);
DISPLAY 0.489362 (-1725 2925);
PAINT SKYBLUE (-1725 2925);
FORCEPROP 1 LAST VOLTAGE 2.5V
J 0
(-1725 3025);
DISPLAY 0.489362 (-1725 3025);
PAINT SKYBLUE (-1725 3025);
FORCEPROP 1 LAST VALUE 470UF
J 0
(-1725 3125);
DISPLAY 0.489362 (-1725 3125);
PAINT SKYBLUE (-1725 3125);
FORCEPROP 1 LAST TOLERANCE 20%
J 0
(-1725 3075);
DISPLAY 0.489362 (-1725 3075);
PAINT SKYBLUE (-1725 3075);
FORCEPROP 1 LAST MATERIAL EMPTY
J 0
(-1725 2975);
DISPLAY 0.489362 (-1725 2975);
PAINT RED (-1725 2975);
FORCEPROP 2 LAST CDS_LIB pure_quanta
J 0
(-1775 3075);
DISPLAY INVISIBLE (-1775 3075);
FORCEPROP 1 LAST PATH I63
J 0
(-1725 3225);
DISPLAY 0.978723 (-1725 3225);
DISPLAY INVISIBLE (-1725 3225);
FORCEPROP 1 LAST PART_NUMBER CH747LM8825
J 0
(-1725 2875);
DISPLAY 0.489362 (-1725 2875);
PAINT SKYBLUE (-1725 2875);
DISPLAY INVISIBLE (-1725 2875);
FORCEADD VCC_CORE..1
(-1275 2125);
FORCEPROP 3 LASTPIN (-1275 2075) SIG_NAME PVDDCR_SOC_P1\g
J 0
(-1265 2085);
DISPLAY 0.659574 (-1265 2085);
PAINT MONO (-1265 2085);
DISPLAY INVISIBLE (-1265 2085);
FORCEPROP 1 LAST HDL_POWER PVDDCR_SOC_P1
J 1
(-1275 2175);
DISPLAY 0.489362 (-1275 2175);
PAINT GREEN (-1275 2175);
FORCEPROP 2 LAST CDS_LIB pure_quanta_power
J 0
(-1275 2125);
DISPLAY INVISIBLE (-1275 2125);
FORCEPROP 1 LAST PATH I64
J 0
(-1225 2150);
DISPLAY 0.872340 (-1225 2150);
PAINT AQUA (-1225 2150);
DISPLAY INVISIBLE (-1225 2150);
FORCEADD UNIVERSAL_GND..1
(-1450 2725);
FORCEPROP 3 LASTPIN (-1450 2775) SIG_NAME GND\g
J 0
(-1440 2785);
DISPLAY 0.659574 (-1440 2785);
PAINT MONO (-1440 2785);
DISPLAY INVISIBLE (-1440 2785);
FORCEPROP 2 LAST CDS_LIB pure_quanta_power
J 0
(-1450 2725);
DISPLAY INVISIBLE (-1450 2725);
FORCEPROP 1 LAST HDL_POWER GND
J 1
(-1425 2650);
DISPLAY 0.872340 (-1425 2650);
PAINT GREEN (-1425 2650);
DISPLAY INVISIBLE (-1425 2650);
FORCEPROP 1 LAST PATH I65
J 0
(-1375 2725);
DISPLAY 0.872340 (-1375 2725);
PAINT AQUA (-1375 2725);
DISPLAY INVISIBLE (-1375 2725);
FORCEADD Q_CAPP..1
(-1450 3075);
FORCEPROP 1 LAST LOCATION PC343
J 0
(-1400 3175);
DISPLAY 0.489362 (-1400 3175);
PAINT SKYBLUE (-1400 3175);
FORCEPROP 0 LAST $SEC 1
J 0
(-1400 3225);
DISPLAY 0.680851 (-1400 3225);
PAINT MONO (-1400 3225);
DISPLAY INVISIBLE (-1400 3225);
FORCEPROP 0 LAST CDS_SEC 1
J 0
(-1400 3225);
DISPLAY 1.021277 (-1400 3225);
DISPLAY INVISIBLE (-1400 3225);
FORCEPROP 1 LASTPIN (-1450 3175) $PN 1
J 0
(-1440 3160);
DISPLAY 0.489362 (-1440 3160);
PAINT MONO (-1440 3160);
FORCEPROP 1 LASTPIN (-1450 2975) $PN 2
J 0
(-1440 2960);
DISPLAY 0.489362 (-1440 2960);
PAINT MONO (-1440 2960);
FORCEPROP 1 LAST VALUE 470UF
J 0
(-1400 3125);
DISPLAY 0.489362 (-1400 3125);
PAINT SKYBLUE (-1400 3125);
FORCEPROP 1 LAST TOLERANCE 20%
J 0
(-1400 3075);
DISPLAY 0.489362 (-1400 3075);
PAINT SKYBLUE (-1400 3075);
FORCEPROP 1 LAST VOLTAGE 2.5V
J 0
(-1400 3025);
DISPLAY 0.489362 (-1400 3025);
PAINT SKYBLUE (-1400 3025);
FORCEPROP 1 LAST MATERIAL SPCAP
J 0
(-1400 2975);
DISPLAY 0.489362 (-1400 2975);
PAINT SKYBLUE (-1400 2975);
FORCEPROP 1 LAST PACK_TYPE SMLF
J 0
(-1400 2925);
DISPLAY 0.489362 (-1400 2925);
PAINT SKYBLUE (-1400 2925);
FORCEPROP 2 LAST CDS_LIB pure_quanta
J 0
(-1450 3075);
DISPLAY INVISIBLE (-1450 3075);
FORCEPROP 1 LAST PATH I66
J 0
(-1400 3225);
DISPLAY 0.978723 (-1400 3225);
DISPLAY INVISIBLE (-1400 3225);
FORCEPROP 1 LAST PART_NUMBER CH747LM8825
J 0
(-1400 2875);
DISPLAY 0.489362 (-1400 2875);
PAINT SKYBLUE (-1400 2875);
DISPLAY INVISIBLE (-1400 2875);
FORCEADD VCC_CORE..1
(-1450 3350);
FORCEPROP 3 LASTPIN (-1450 3300) SIG_NAME PVDDCR_SOC_P1\g
J 0
(-1440 3310);
DISPLAY 0.659574 (-1440 3310);
PAINT MONO (-1440 3310);
DISPLAY INVISIBLE (-1440 3310);
FORCEPROP 1 LAST HDL_POWER PVDDCR_SOC_P1
J 1
(-1450 3400);
DISPLAY 0.489362 (-1450 3400);
PAINT GREEN (-1450 3400);
FORCEPROP 2 LAST CDS_LIB pure_quanta_power
J 0
(-1450 3350);
DISPLAY INVISIBLE (-1450 3350);
FORCEPROP 1 LAST PATH I67
J 0
(-1400 3375);
DISPLAY 0.872340 (-1400 3375);
PAINT AQUA (-1400 3375);
DISPLAY INVISIBLE (-1400 3375);
FORCEADD Q_CAP..1
(-3950 4975);
FORCEPROP 1 LAST LOCATION PC333
J 0
(-3900 5100);
DISPLAY 0.489362 (-3900 5100);
PAINT SKYBLUE (-3900 5100);
FORCEPROP 0 LAST $SEC 1
J 0
(-3900 5125);
DISPLAY 0.680851 (-3900 5125);
PAINT MONO (-3900 5125);
DISPLAY INVISIBLE (-3900 5125);
FORCEPROP 0 LAST CDS_SEC 1
J 0
(-3900 5125);
DISPLAY 1.021277 (-3900 5125);
DISPLAY INVISIBLE (-3900 5125);
FORCEPROP 1 LASTPIN (-3950 5075) $PN 1
J 0
(-3940 5055);
DISPLAY 0.489362 (-3940 5055);
PAINT MONO (-3940 5055);
FORCEPROP 1 LASTPIN (-3950 4875) $PN 2
J 0
(-3940 4855);
DISPLAY 0.489362 (-3940 4855);
PAINT MONO (-3940 4855);
FORCEPROP 1 LAST PACK_TYPE 0402
J 0
(-3900 4800);
DISPLAY 0.489362 (-3900 4800);
PAINT SKYBLUE (-3900 4800);
FORCEPROP 1 LAST MATERIAL X7R
J 0
(-3900 4900);
DISPLAY 0.489362 (-3900 4900);
PAINT SKYBLUE (-3900 4900);
FORCEPROP 1 LAST TOLERANCE 10%
J 0
(-3900 4950);
DISPLAY 0.489362 (-3900 4950);
PAINT SKYBLUE (-3900 4950);
FORCEPROP 1 LAST VOLTAGE 16V
J 0
(-3900 5000);
DISPLAY 0.489362 (-3900 5000);
PAINT SKYBLUE (-3900 5000);
FORCEPROP 1 LAST VALUE 0.22UF
J 0
(-3900 5050);
DISPLAY 0.489362 (-3900 5050);
PAINT SKYBLUE (-3900 5050);
FORCEPROP 2 LAST CDS_LIB pure_quanta
J 0
(-3950 4975);
DISPLAY INVISIBLE (-3950 4975);
FORCEPROP 1 LAST PATH I68
J 0
(-3900 5125);
DISPLAY 0.978723 (-3900 5125);
PAINT WHITE (-3900 5125);
DISPLAY INVISIBLE (-3900 5125);
FORCEPROP 1 LAST PART_NUMBER CH4223K1B00
J 0
(-3900 4850);
DISPLAY 0.489362 (-3900 4850);
PAINT SKYBLUE (-3900 4850);
DISPLAY INVISIBLE (-3900 4850);
FORCEADD Q_INDUCTOR4P_14..1
(-3200 4625);
FORCEPROP 1 LAST LOCATION PL35
J 0
(-3425 4880);
DISPLAY 0.489362 (-3425 4880);
PAINT SKYBLUE (-3425 4880);
FORCEPROP 0 LAST $SEC 1
J 0
(-3425 5025);
DISPLAY 0.680851 (-3425 5025);
PAINT MONO (-3425 5025);
DISPLAY INVISIBLE (-3425 5025);
FORCEPROP 0 LAST CDS_SEC 1
J 0
(-3425 5025);
DISPLAY 1.021277 (-3425 5025);
DISPLAY INVISIBLE (-3425 5025);
FORCEPROP 0 LASTPIN (-3600 4750) $PN 1
J 2
(-3610 4760);
DISPLAY 0.489362 (-3610 4760);
PAINT MONO (-3610 4760);
FORCEPROP 0 LASTPIN (-3600 4500) $PN 2
J 2
(-3610 4510);
DISPLAY 0.489362 (-3610 4510);
PAINT MONO (-3610 4510);
FORCEPROP 0 LASTPIN (-2800 4500) $PN 3
J 0
(-2790 4510);
DISPLAY 0.489362 (-2790 4510);
PAINT MONO (-2790 4510);
FORCEPROP 0 LASTPIN (-2800 4750) $PN 4
J 0
(-2790 4760);
DISPLAY 0.489362 (-2790 4760);
PAINT MONO (-2790 4760);
FORCEPROP 1 LAST MATERIAL IND
J 0
(-3425 4835);
DISPLAY 0.489362 (-3425 4835);
PAINT SKYBLUE (-3425 4835);
FORCEPROP 2 LAST PART_TYPE SMLF
J 0
(-3425 4975);
DISPLAY 1.021277 (-3425 4975);
FORCEPROP 2 LAST VALUE 150NH
J 0
(-3425 4925);
DISPLAY 0.489362 (-3425 4925);
PAINT SKYBLUE (-3425 4925);
FORCEPROP 1 LAST NEEDS_NO_SIZE TRUE
J 0
(-3200 4625);
DISPLAY 0.468085 (-3200 4625);
PAINT GREEN (-3200 4625);
DISPLAY INVISIBLE (-3200 4625);
FORCEPROP 2 LAST CDS_LIB pure_quanta
J 0
(-3200 4625);
DISPLAY INVISIBLE (-3200 4625);
FORCEPROP 1 LAST PATH I69
J 0
(-3000 4780);
DISPLAY 0.723404 (-3000 4780);
PAINT GREEN (-3000 4780);
DISPLAY INVISIBLE (-3000 4780);
FORCEPROP 1 LAST PART_NUMBER CV+15^0TZ04
J 0
(-3425 4785);
DISPLAY 0.489362 (-3425 4785);
PAINT SKYBLUE (-3425 4785);
DISPLAY INVISIBLE (-3425 4785);
FORCEADD OFFPAGE..1
(-7125 1375);
FORCEPROP 2 LAST $XR0 210 
J 0
(-7407 1375);
DISPLAY 0.638298 (-7407 1375);
PAINT MONO (-7407 1375);
FORCEPROP 2 LAST CDS_LIB standard
J 2
(-7125 1375);
DISPLAY INVISIBLE (-7125 1375);
FORCEPROP 1 LAST OFFPAGE TRUE
J 0
(-6800 1250);
DISPLAY 0.872340 (-6800 1250);
PAINT GREEN (-6800 1250);
DISPLAY INVISIBLE (-6800 1250);
FORCEPROP 1 LAST COMMENT_BODY TRUE
J 0
(-7000 1275);
DISPLAY 0.872340 (-7000 1275);
PAINT GREEN (-7000 1275);
DISPLAY INVISIBLE (-7000 1275);
FORCEPROP 2 LAST PATH I7
J 0
(-7400 1425);
DISPLAY 0.680851 (-7400 1425);
DISPLAY INVISIBLE (-7400 1425);
FORCEADD UNIVERSAL_GND..1
(-3925 5275);
FORCEPROP 3 LASTPIN (-3925 5325) SIG_NAME GND\g
J 0
(-3915 5335);
DISPLAY 0.659574 (-3915 5335);
PAINT MONO (-3915 5335);
DISPLAY INVISIBLE (-3915 5335);
FORCEPROP 2 LAST CDS_LIB pure_quanta_power
J 0
(-3925 5275);
DISPLAY INVISIBLE (-3925 5275);
FORCEPROP 1 LAST HDL_POWER GND
J 1
(-3900 5200);
DISPLAY 0.872340 (-3900 5200);
PAINT GREEN (-3900 5200);
DISPLAY INVISIBLE (-3900 5200);
FORCEPROP 1 LAST PATH I70
J 0
(-3850 5275);
DISPLAY 0.872340 (-3850 5275);
PAINT AQUA (-3850 5275);
DISPLAY INVISIBLE (-3850 5275);
FORCEADD Q_CAP..1
(-3950 5600);
FORCEPROP 1 LAST LOCATION PC334_1
J 0
(-3900 5700);
DISPLAY 0.489362 (-3900 5700);
PAINT SKYBLUE (-3900 5700);
FORCEPROP 0 LAST $SEC 1
J 0
(-3900 5725);
DISPLAY 0.680851 (-3900 5725);
PAINT MONO (-3900 5725);
DISPLAY INVISIBLE (-3900 5725);
FORCEPROP 0 LAST CDS_SEC 1
J 0
(-3900 5725);
DISPLAY 0.680851 (-3900 5725);
DISPLAY INVISIBLE (-3900 5725);
FORCEPROP 1 LASTPIN (-3950 5700) $PN 1
J 0
(-3940 5680);
DISPLAY 0.787234 (-3940 5680);
PAINT MONO (-3940 5680);
DISPLAY INVISIBLE (-3940 5680);
FORCEPROP 1 LASTPIN (-3950 5500) $PN 2
J 0
(-3940 5480);
DISPLAY 0.787234 (-3940 5480);
PAINT MONO (-3940 5480);
DISPLAY INVISIBLE (-3940 5480);
FORCEPROP 1 LAST VALUE 22UF
J 0
(-3900 5650);
DISPLAY 0.489362 (-3900 5650);
PAINT SKYBLUE (-3900 5650);
FORCEPROP 1 LAST TOLERANCE 20%
J 0
(-3900 5550);
DISPLAY 0.489362 (-3900 5550);
PAINT SKYBLUE (-3900 5550);
FORCEPROP 1 LAST VOLTAGE 16V
J 0
(-3900 5600);
DISPLAY 0.489362 (-3900 5600);
PAINT SKYBLUE (-3900 5600);
FORCEPROP 1 LAST MATERIAL X6S
J 0
(-3900 5500);
DISPLAY 0.489362 (-3900 5500);
PAINT SKYBLUE (-3900 5500);
FORCEPROP 1 LAST PACK_TYPE C0805
J 0
(-3900 5400);
DISPLAY 0.489362 (-3900 5400);
PAINT SKYBLUE (-3900 5400);
FORCEPROP 2 LAST CDS_LIB pure_quanta
J 0
(-3950 5600);
DISPLAY INVISIBLE (-3950 5600);
FORCEPROP 1 LAST PATH I71
J 0
(-3900 5750);
DISPLAY 0.978723 (-3900 5750);
PAINT WHITE (-3900 5750);
DISPLAY INVISIBLE (-3900 5750);
FORCEPROP 1 LAST PART_NUMBER CH6223MEA01
J 0
(-3900 5450);
DISPLAY 0.489362 (-3900 5450);
PAINT SKYBLUE (-3900 5450);
DISPLAY INVISIBLE (-3900 5450);
FORCEADD VCC_CORE..1
(-3925 5875);
FORCEPROP 3 LASTPIN (-3925 5825) SIG_NAME SW_P12V_AUX_PVDDCR_SOC_P1_FLT\g
J 0
(-3915 5835);
DISPLAY 0.659574 (-3915 5835);
PAINT MONO (-3915 5835);
DISPLAY INVISIBLE (-3915 5835);
FORCEPROP 1 LAST HDL_POWER SW_P12V_AUX_PVDDCR_SOC_P1_FLT
J 1
(-3925 5925);
DISPLAY 0.489362 (-3925 5925);
PAINT GREEN (-3925 5925);
FORCEPROP 2 LAST CDS_LIB pure_quanta_power
J 0
(-3925 5875);
DISPLAY INVISIBLE (-3925 5875);
FORCEPROP 1 LAST PATH I72
J 0
(-3875 5900);
DISPLAY 0.872340 (-3875 5900);
PAINT AQUA (-3875 5900);
DISPLAY INVISIBLE (-3875 5900);
FORCEADD Q_CAPP..1
(-3450 5600);
FORCEPROP 1 LAST LOCATION PC336
J 0
(-3400 5700);
DISPLAY 0.489362 (-3400 5700);
PAINT SKYBLUE (-3400 5700);
FORCEPROP 0 LAST $SEC 1
J 0
(-3400 5750);
DISPLAY 0.680851 (-3400 5750);
PAINT MONO (-3400 5750);
DISPLAY INVISIBLE (-3400 5750);
FORCEPROP 0 LAST CDS_SEC 1
J 0
(-3400 5750);
DISPLAY 1.021277 (-3400 5750);
DISPLAY INVISIBLE (-3400 5750);
FORCEPROP 1 LASTPIN (-3450 5700) $PN 1
J 0
(-3440 5685);
DISPLAY 0.489362 (-3440 5685);
PAINT MONO (-3440 5685);
FORCEPROP 1 LASTPIN (-3450 5500) $PN 2
J 0
(-3440 5485);
DISPLAY 0.489362 (-3440 5485);
PAINT MONO (-3440 5485);
FORCEPROP 1 LAST VALUE 270UF
J 0
(-3400 5650);
DISPLAY 0.489362 (-3400 5650);
PAINT SKYBLUE (-3400 5650);
FORCEPROP 1 LAST VOLTAGE 16V
J 0
(-3400 5550);
DISPLAY 0.489362 (-3400 5550);
PAINT SKYBLUE (-3400 5550);
FORCEPROP 1 LAST TOLERANCE 20%
J 0
(-3400 5600);
DISPLAY 0.489362 (-3400 5600);
PAINT SKYBLUE (-3400 5600);
FORCEPROP 1 LAST MATERIAL OSCON
J 0
(-3400 5500);
DISPLAY 0.489362 (-3400 5500);
PAINT SKYBLUE (-3400 5500);
FORCEPROP 1 LAST PACK_TYPE THLF
J 0
(-3400 5450);
DISPLAY 0.489362 (-3400 5450);
PAINT SKYBLUE (-3400 5450);
FORCEPROP 2 LAST CDS_LIB pure_quanta
J 0
(-3450 5600);
DISPLAY INVISIBLE (-3450 5600);
FORCEPROP 1 LAST PATH I73
J 0
(-3400 5750);
DISPLAY 0.978723 (-3400 5750);
DISPLAY INVISIBLE (-3400 5750);
FORCEPROP 1 LAST PART_NUMBER CC72703MD38
J 0
(-3400 5400);
DISPLAY 0.489362 (-3400 5400);
PAINT SKYBLUE (-3400 5400);
DISPLAY INVISIBLE (-3400 5400);
FORCEADD Q_INDUCTOR..1
(-3075 5800);
FORCEPROP 1 LAST LOCATION PL37
J 0
(-3200 5960);
DISPLAY 0.489362 (-3200 5960);
PAINT SKYBLUE (-3200 5960);
FORCEPROP 0 LAST $SEC 1
J 0
(-3200 6075);
DISPLAY 0.680851 (-3200 6075);
PAINT MONO (-3200 6075);
DISPLAY INVISIBLE (-3200 6075);
FORCEPROP 0 LAST CDS_SEC 1
J 0
(-3200 6075);
DISPLAY 1.021277 (-3200 6075);
DISPLAY INVISIBLE (-3200 6075);
FORCEPROP 0 LASTPIN (-3175 5775) $PN 1
J 2
(-3185 5785);
DISPLAY 0.489362 (-3185 5785);
PAINT MONO (-3185 5785);
FORCEPROP 0 LASTPIN (-2975 5775) $PN 2
J 0
(-2965 5785);
DISPLAY 0.489362 (-2965 5785);
PAINT MONO (-2965 5785);
FORCEPROP 2 LAST VALUE 50NH/86A
J 0
(-3200 6050);
DISPLAY 0.489362 (-3200 6050);
PAINT SKYBLUE (-3200 6050);
FORCEPROP 1 LAST MATERIAL IND
J 0
(-3200 5855);
DISPLAY 0.489362 (-3200 5855);
PAINT SKYBLUE (-3200 5855);
FORCEPROP 2 LAST PACK_TYPE SMLF
J 0
(-3200 6000);
DISPLAY 0.489362 (-3200 6000);
PAINT SKYBLUE (-3200 6000);
FORCEPROP 2 LAST CDS_LIB pure_quanta
J 0
(-3075 5800);
DISPLAY INVISIBLE (-3075 5800);
FORCEPROP 1 LAST NEEDS_NO_SIZE TRUE
J 0
(-3075 5800);
DISPLAY 0.468085 (-3075 5800);
PAINT GREEN (-3075 5800);
DISPLAY INVISIBLE (-3075 5800);
FORCEPROP 1 LAST PATH I74
J 0
(-3000 5855);
DISPLAY 0.723404 (-3000 5855);
PAINT GREEN (-3000 5855);
DISPLAY INVISIBLE (-3000 5855);
FORCEPROP 1 LAST PART_NUMBER CVA50^0MZ09
J 0
(-3200 5910);
DISPLAY 0.489362 (-3200 5910);
PAINT SKYBLUE (-3200 5910);
DISPLAY INVISIBLE (-3200 5910);
FORCEADD UNIVERSAL_GND..1
(-2325 4375);
FORCEPROP 3 LASTPIN (-2325 4425) SIG_NAME GND\g
J 0
(-2315 4435);
DISPLAY 0.659574 (-2315 4435);
PAINT MONO (-2315 4435);
DISPLAY INVISIBLE (-2315 4435);
FORCEPROP 2 LAST CDS_LIB pure_quanta_power
J 0
(-2325 4375);
DISPLAY INVISIBLE (-2325 4375);
FORCEPROP 1 LAST HDL_POWER GND
J 1
(-2300 4300);
DISPLAY 0.872340 (-2300 4300);
PAINT GREEN (-2300 4300);
DISPLAY INVISIBLE (-2300 4300);
FORCEPROP 1 LAST PATH I75
J 0
(-2250 4375);
DISPLAY 0.872340 (-2250 4375);
PAINT AQUA (-2250 4375);
DISPLAY INVISIBLE (-2250 4375);
FORCEADD UNIVERSAL_GND..1
(-2625 5325);
FORCEPROP 3 LASTPIN (-2625 5375) SIG_NAME GND\g
J 0
(-2615 5385);
DISPLAY 0.659574 (-2615 5385);
PAINT MONO (-2615 5385);
DISPLAY INVISIBLE (-2615 5385);
FORCEPROP 2 LAST CDS_LIB pure_quanta_power
J 0
(-2625 5325);
DISPLAY INVISIBLE (-2625 5325);
FORCEPROP 1 LAST HDL_POWER GND
J 1
(-2600 5250);
DISPLAY 0.872340 (-2600 5250);
PAINT GREEN (-2600 5250);
DISPLAY INVISIBLE (-2600 5250);
FORCEPROP 1 LAST PATH I76
J 0
(-2550 5325);
DISPLAY 0.872340 (-2550 5325);
PAINT AQUA (-2550 5325);
DISPLAY INVISIBLE (-2550 5325);
FORCEADD Q_CAP..1
(-2625 5625);
FORCEPROP 1 LAST LOCATION PC6007
J 0
(-2575 5725);
DISPLAY 0.489362 (-2575 5725);
PAINT SKYBLUE (-2575 5725);
FORCEPROP 0 LAST $SEC 1
J 0
(-2575 5750);
DISPLAY 0.680851 (-2575 5750);
PAINT MONO (-2575 5750);
DISPLAY INVISIBLE (-2575 5750);
FORCEPROP 0 LAST CDS_SEC 1
J 0
(-2575 5750);
DISPLAY 0.680851 (-2575 5750);
DISPLAY INVISIBLE (-2575 5750);
FORCEPROP 1 LASTPIN (-2625 5725) $PN 1
J 0
(-2615 5705);
DISPLAY 0.787234 (-2615 5705);
PAINT MONO (-2615 5705);
FORCEPROP 1 LASTPIN (-2625 5525) $PN 2
J 0
(-2615 5505);
DISPLAY 0.787234 (-2615 5505);
PAINT MONO (-2615 5505);
FORCEPROP 1 LAST MATERIAL X7R
J 0
(-2575 5525);
DISPLAY 0.489362 (-2575 5525);
PAINT SKYBLUE (-2575 5525);
FORCEPROP 1 LAST VALUE 0.1UF
J 0
(-2575 5675);
DISPLAY 0.489362 (-2575 5675);
PAINT SKYBLUE (-2575 5675);
FORCEPROP 1 LAST PACK_TYPE 0402
J 0
(-2575 5425);
DISPLAY 0.489362 (-2575 5425);
PAINT SKYBLUE (-2575 5425);
FORCEPROP 1 LAST TOLERANCE 10%
J 0
(-2575 5575);
DISPLAY 0.489362 (-2575 5575);
PAINT SKYBLUE (-2575 5575);
FORCEPROP 1 LAST VOLTAGE 25V
J 0
(-2575 5625);
DISPLAY 0.489362 (-2575 5625);
PAINT SKYBLUE (-2575 5625);
FORCEPROP 2 LAST CDS_LIB pure_quanta
J 0
(-2625 5625);
DISPLAY INVISIBLE (-2625 5625);
FORCEPROP 1 LAST PATH I77
J 0
(-2575 5775);
DISPLAY 0.978723 (-2575 5775);
PAINT WHITE (-2575 5775);
DISPLAY INVISIBLE (-2575 5775);
FORCEPROP 1 LAST PART_NUMBER CH4104K1B00
J 0
(-2575 5475);
DISPLAY 0.489362 (-2575 5475);
PAINT SKYBLUE (-2575 5475);
DISPLAY INVISIBLE (-2575 5475);
FORCEADD VCC_CORE..1
(-2575 5875);
FORCEPROP 3 LASTPIN (-2575 5825) SIG_NAME P12V_AUX\g
J 0
(-2565 5835);
DISPLAY 0.659574 (-2565 5835);
PAINT MONO (-2565 5835);
DISPLAY INVISIBLE (-2565 5835);
FORCEPROP 1 LAST HDL_POWER P12V_AUX
J 1
(-2575 5925);
DISPLAY 0.489362 (-2575 5925);
PAINT GREEN (-2575 5925);
FORCEPROP 2 LAST CDS_LIB pure_quanta_power
J 0
(-2575 5875);
DISPLAY INVISIBLE (-2575 5875);
FORCEPROP 1 LAST PATH I78
J 0
(-2525 5900);
DISPLAY 0.872340 (-2525 5900);
PAINT AQUA (-2525 5900);
DISPLAY INVISIBLE (-2525 5900);
FORCEADD Q_CAP..1
(-1975 4550);
FORCEPROP 1 LAST LOCATION PC338
J 0
(-1900 4675);
DISPLAY 0.489362 (-1900 4675);
PAINT SKYBLUE (-1900 4675);
FORCEPROP 0 LAST $SEC 1
J 0
(-1925 4675);
DISPLAY 0.680851 (-1925 4675);
PAINT MONO (-1925 4675);
DISPLAY INVISIBLE (-1925 4675);
FORCEPROP 0 LAST CDS_SEC 1
J 0
(-1925 4675);
DISPLAY 1.021277 (-1925 4675);
DISPLAY INVISIBLE (-1925 4675);
FORCEPROP 1 LASTPIN (-1975 4650) $PN 1
J 0
(-1965 4630);
DISPLAY 0.489362 (-1965 4630);
PAINT MONO (-1965 4630);
FORCEPROP 1 LASTPIN (-1975 4450) $PN 2
J 0
(-1965 4430);
DISPLAY 0.489362 (-1965 4430);
PAINT MONO (-1965 4430);
FORCEPROP 1 LAST PACK_TYPE 0402
J 0
(-1900 4375);
DISPLAY 0.489362 (-1900 4375);
PAINT SKYBLUE (-1900 4375);
FORCEPROP 1 LAST VOLTAGE 25V
J 0
(-1900 4575);
DISPLAY 0.489362 (-1900 4575);
PAINT SKYBLUE (-1900 4575);
FORCEPROP 1 LAST TOLERANCE 10%
J 0
(-1900 4525);
DISPLAY 0.489362 (-1900 4525);
PAINT SKYBLUE (-1900 4525);
FORCEPROP 1 LAST MATERIAL X7R
J 0
(-1900 4475);
DISPLAY 0.489362 (-1900 4475);
PAINT SKYBLUE (-1900 4475);
FORCEPROP 1 LAST VALUE 0.1UF
J 0
(-1900 4625);
DISPLAY 0.489362 (-1900 4625);
PAINT SKYBLUE (-1900 4625);
FORCEPROP 2 LAST CDS_LIB pure_quanta
J 0
(-1975 4550);
DISPLAY INVISIBLE (-1975 4550);
FORCEPROP 1 LAST PATH I79
J 0
(-1925 4700);
DISPLAY 0.978723 (-1925 4700);
PAINT WHITE (-1925 4700);
DISPLAY INVISIBLE (-1925 4700);
FORCEPROP 1 LAST PART_NUMBER CH4104K1B00
J 0
(-1900 4425);
DISPLAY 0.489362 (-1900 4425);
PAINT SKYBLUE (-1900 4425);
DISPLAY INVISIBLE (-1900 4425);
FORCEADD Q_RES..1
(-7175 1675);
FORCEPROP 1 LAST LOCATION PR208
J 0
(-7175 1725);
DISPLAY 0.489362 (-7175 1725);
PAINT SKYBLUE (-7175 1725);
FORCEPROP 0 LAST $SEC 1
J 0
(-7175 1750);
DISPLAY 0.680851 (-7175 1750);
PAINT MONO (-7175 1750);
DISPLAY INVISIBLE (-7175 1750);
FORCEPROP 0 LAST CDS_SEC 1
J 0
(-7175 1750);
DISPLAY 1.021277 (-7175 1750);
DISPLAY INVISIBLE (-7175 1750);
FORCEPROP 1 LASTPIN (-7275 1675) $PN 1
J 0
(-7263 1687);
DISPLAY 0.489362 (-7263 1687);
PAINT MONO (-7263 1687);
FORCEPROP 1 LASTPIN (-7075 1675) $PN 2
J 0
(-7113 1687);
DISPLAY 0.489362 (-7113 1687);
PAINT MONO (-7113 1687);
FORCEPROP 1 LAST PACK_TYPE 0402LF
J 0
(-7075 1625);
DISPLAY 0.489362 (-7075 1625);
PAINT SKYBLUE (-7075 1625);
FORCEPROP 1 LAST WATTAGE 1/16W
J 0
(-7075 1575);
DISPLAY 0.489362 (-7075 1575);
PAINT SKYBLUE (-7075 1575);
FORCEPROP 1 LAST VALUE 8.87K
J 2
(-7300 1700);
DISPLAY 0.489362 (-7300 1700);
PAINT SKYBLUE (-7300 1700);
FORCEPROP 1 LAST TOLERANCE 1%
J 0
(-7050 1700);
DISPLAY 0.489362 (-7050 1700);
PAINT SKYBLUE (-7050 1700);
FORCEPROP 1 LAST MATERIAL EMPTY
J 0
(-7475 1575);
DISPLAY 0.489362 (-7475 1575);
PAINT RED (-7475 1575);
FORCEPROP 2 LAST CDS_LIB pure_quanta
J 0
(-7175 1675);
DISPLAY INVISIBLE (-7175 1675);
FORCEPROP 1 LAST PATH I8
J 0
(-7225 1825);
DISPLAY 0.978723 (-7225 1825);
PAINT WHITE (-7225 1825);
DISPLAY INVISIBLE (-7225 1825);
FORCEPROP 1 LAST PART_NUMBER CS28872FB01
J 0
(-7475 1625);
DISPLAY 0.489362 (-7475 1625);
PAINT SKYBLUE (-7475 1625);
DISPLAY INVISIBLE (-7475 1625);
FORCEADD Q_CAP..1
(-1575 4575);
FORCEPROP 1 LAST LOCATION PC341_1
J 0
(-1525 4675);
DISPLAY 0.489362 (-1525 4675);
PAINT SKYBLUE (-1525 4675);
FORCEPROP 0 LAST $SEC 1
J 0
(-1525 4700);
DISPLAY 0.680851 (-1525 4700);
PAINT MONO (-1525 4700);
DISPLAY INVISIBLE (-1525 4700);
FORCEPROP 0 LAST CDS_SEC 1
J 0
(-1525 4700);
DISPLAY 1.021277 (-1525 4700);
DISPLAY INVISIBLE (-1525 4700);
FORCEPROP 1 LASTPIN (-1575 4675) $PN 1
J 0
(-1565 4655);
DISPLAY 0.489362 (-1565 4655);
PAINT MONO (-1565 4655);
FORCEPROP 1 LASTPIN (-1575 4475) $PN 2
J 0
(-1565 4455);
DISPLAY 0.489362 (-1565 4455);
PAINT MONO (-1565 4455);
FORCEPROP 1 LAST TOLERANCE 20%
J 0
(-1525 4525);
DISPLAY 0.489362 (-1525 4525);
PAINT SKYBLUE (-1525 4525);
FORCEPROP 1 LAST MATERIAL X6S
J 0
(-1525 4475);
DISPLAY 0.489362 (-1525 4475);
PAINT SKYBLUE (-1525 4475);
FORCEPROP 1 LAST PACK_TYPE C0805
J 0
(-1525 4375);
DISPLAY 0.489362 (-1525 4375);
PAINT SKYBLUE (-1525 4375);
FORCEPROP 1 LAST VOLTAGE 4V
J 0
(-1525 4575);
DISPLAY 0.489362 (-1525 4575);
PAINT SKYBLUE (-1525 4575);
FORCEPROP 1 LAST VALUE 22UF
J 0
(-1525 4625);
DISPLAY 0.489362 (-1525 4625);
PAINT SKYBLUE (-1525 4625);
FORCEPROP 2 LAST CDS_LIB pure_quanta
J 0
(-1575 4575);
DISPLAY INVISIBLE (-1575 4575);
FORCEPROP 1 LAST PATH I80
J 0
(-1525 4725);
DISPLAY 0.978723 (-1525 4725);
PAINT WHITE (-1525 4725);
DISPLAY INVISIBLE (-1525 4725);
FORCEPROP 1 LAST PART_NUMBER CH622KMEA03
J 0
(-1525 4425);
DISPLAY 0.489362 (-1525 4425);
PAINT SKYBLUE (-1525 4425);
DISPLAY INVISIBLE (-1525 4425);
FORCEADD Q_CAP..1
(-1150 4575);
FORCEPROP 1 LAST LOCATION PC344_1
J 0
(-1100 4675);
DISPLAY 0.489362 (-1100 4675);
PAINT SKYBLUE (-1100 4675);
FORCEPROP 0 LAST $SEC 1
J 0
(-1100 4700);
DISPLAY 0.680851 (-1100 4700);
PAINT MONO (-1100 4700);
DISPLAY INVISIBLE (-1100 4700);
FORCEPROP 0 LAST CDS_SEC 1
J 0
(-1100 4700);
DISPLAY 1.021277 (-1100 4700);
DISPLAY INVISIBLE (-1100 4700);
FORCEPROP 1 LASTPIN (-1150 4675) $PN 1
J 0
(-1140 4655);
DISPLAY 0.489362 (-1140 4655);
PAINT MONO (-1140 4655);
FORCEPROP 1 LASTPIN (-1150 4475) $PN 2
J 0
(-1140 4455);
DISPLAY 0.489362 (-1140 4455);
PAINT MONO (-1140 4455);
FORCEPROP 1 LAST PACK_TYPE C0805
J 0
(-1100 4425);
DISPLAY 0.489362 (-1100 4425);
PAINT SKYBLUE (-1100 4425);
FORCEPROP 1 LAST MATERIAL X6S
J 0
(-1100 4475);
DISPLAY 0.489362 (-1100 4475);
PAINT SKYBLUE (-1100 4475);
FORCEPROP 1 LAST VALUE 22UF
J 0
(-1100 4625);
DISPLAY 0.489362 (-1100 4625);
PAINT SKYBLUE (-1100 4625);
FORCEPROP 1 LAST VOLTAGE 4V
J 0
(-1100 4575);
DISPLAY 0.489362 (-1100 4575);
PAINT SKYBLUE (-1100 4575);
FORCEPROP 1 LAST TOLERANCE 20%
J 0
(-1100 4525);
DISPLAY 0.489362 (-1100 4525);
PAINT SKYBLUE (-1100 4525);
FORCEPROP 2 LAST CDS_LIB pure_quanta
J 0
(-1150 4575);
DISPLAY INVISIBLE (-1150 4575);
FORCEPROP 1 LAST PATH I81
J 0
(-1100 4725);
DISPLAY 0.978723 (-1100 4725);
PAINT WHITE (-1100 4725);
DISPLAY INVISIBLE (-1100 4725);
FORCEPROP 1 LAST PART_NUMBER CH622KMEA03
J 0
(-1100 4425);
DISPLAY 0.489362 (-1100 4425);
PAINT SKYBLUE (-1100 4425);
DISPLAY INVISIBLE (-1100 4425);
FORCEADD UNIVERSAL_GND..1
(-875 4175);
FORCEPROP 3 LASTPIN (-875 4225) SIG_NAME GND\g
J 0
(-865 4235);
DISPLAY 0.659574 (-865 4235);
PAINT MONO (-865 4235);
DISPLAY INVISIBLE (-865 4235);
FORCEPROP 2 LAST CDS_LIB pure_quanta_power
J 0
(-875 4175);
DISPLAY INVISIBLE (-875 4175);
FORCEPROP 1 LAST HDL_POWER GND
J 1
(-850 4100);
DISPLAY 0.872340 (-850 4100);
PAINT GREEN (-850 4100);
DISPLAY INVISIBLE (-850 4100);
FORCEPROP 1 LAST PATH I82
J 0
(-800 4175);
DISPLAY 0.872340 (-800 4175);
PAINT AQUA (-800 4175);
DISPLAY INVISIBLE (-800 4175);
FORCEADD Q_RES..2
(-875 4550);
FORCEPROP 1 LAST LOCATION PR339
J 0
(-830 4675);
DISPLAY 0.489362 (-830 4675);
PAINT SKYBLUE (-830 4675);
FORCEPROP 0 LAST $SEC 1
J 0
(-825 4700);
DISPLAY 0.680851 (-825 4700);
PAINT MONO (-825 4700);
DISPLAY INVISIBLE (-825 4700);
FORCEPROP 0 LAST CDS_SEC 1
J 0
(-825 4700);
DISPLAY 1.021277 (-825 4700);
DISPLAY INVISIBLE (-825 4700);
FORCEPROP 1 LASTPIN (-875 4650) $PN 1
J 0
(-870 4612);
DISPLAY 0.787234 (-870 4612);
PAINT MONO (-870 4612);
DISPLAY INVISIBLE (-870 4612);
FORCEPROP 1 LASTPIN (-875 4450) $PN 2
J 0
(-870 4460);
DISPLAY 0.787234 (-870 4460);
PAINT MONO (-870 4460);
DISPLAY INVISIBLE (-870 4460);
FORCEPROP 1 LAST PACK_TYPE 0402LF
J 0
(-835 4375);
DISPLAY 0.489362 (-835 4375);
PAINT SKYBLUE (-835 4375);
FORCEPROP 1 LAST MATERIAL CHIP
J 0
(-835 4475);
DISPLAY 0.489362 (-835 4475);
PAINT SKYBLUE (-835 4475);
FORCEPROP 1 LAST TOLERANCE 1%
J 0
(-830 4575);
DISPLAY 0.489362 (-830 4575);
PAINT SKYBLUE (-830 4575);
FORCEPROP 1 LAST VALUE 1K
J 0
(-830 4625);
DISPLAY 0.489362 (-830 4625);
PAINT SKYBLUE (-830 4625);
FORCEPROP 1 LAST WATTAGE 1/16W
J 0
(-835 4525);
DISPLAY 0.489362 (-835 4525);
PAINT SKYBLUE (-835 4525);
FORCEPROP 2 LAST CDS_LIB pure_quanta
J 0
(-875 4550);
DISPLAY INVISIBLE (-875 4550);
FORCEPROP 1 LAST PATH I83
J 0
(-825 4725);
DISPLAY 0.978723 (-825 4725);
PAINT WHITE (-825 4725);
DISPLAY INVISIBLE (-825 4725);
FORCEPROP 1 LAST PART_NUMBER CS21002FB06
J 0
(-835 4425);
DISPLAY 0.489362 (-835 4425);
PAINT SKYBLUE (-835 4425);
DISPLAY INVISIBLE (-835 4425);
FORCEADD VCC_CORE..1
(-875 4875);
FORCEPROP 3 LASTPIN (-875 4825) SIG_NAME PVDDCR_SOC_P1\g
J 0
(-865 4835);
DISPLAY 0.659574 (-865 4835);
PAINT MONO (-865 4835);
DISPLAY INVISIBLE (-865 4835);
FORCEPROP 1 LAST HDL_POWER PVDDCR_SOC_P1
J 1
(-875 4925);
DISPLAY 0.489362 (-875 4925);
PAINT GREEN (-875 4925);
FORCEPROP 2 LAST CDS_LIB pure_quanta_power
J 0
(-875 4875);
DISPLAY INVISIBLE (-875 4875);
FORCEPROP 1 LAST PATH I84
J 0
(-825 4900);
DISPLAY 0.872340 (-825 4900);
PAINT AQUA (-825 4900);
DISPLAY INVISIBLE (-825 4900);
FORCEADD Q_RES..1
(-4275 800);
FORCEPROP 1 LAST LOCATION PR212
J 0
(-4300 850);
DISPLAY 0.489362 (-4300 850);
PAINT SKYBLUE (-4300 850);
FORCEPROP 0 LAST $SEC 1
J 0
(-4275 875);
DISPLAY 0.680851 (-4275 875);
PAINT MONO (-4275 875);
DISPLAY INVISIBLE (-4275 875);
FORCEPROP 0 LAST CDS_SEC 1
J 0
(-4275 875);
DISPLAY 1.021277 (-4275 875);
DISPLAY INVISIBLE (-4275 875);
FORCEPROP 1 LASTPIN (-4375 800) $PN 1
J 0
(-4363 812);
DISPLAY 0.489362 (-4363 812);
PAINT MONO (-4363 812);
FORCEPROP 1 LASTPIN (-4175 800) $PN 2
J 0
(-4213 812);
DISPLAY 0.489362 (-4213 812);
PAINT MONO (-4213 812);
FORCEPROP 1 LAST VALUE 0
J 2
(-4400 825);
DISPLAY 0.489362 (-4400 825);
PAINT SKYBLUE (-4400 825);
FORCEPROP 1 LAST MATERIAL CHIP
J 0
(-4525 700);
DISPLAY 0.489362 (-4525 700);
PAINT SKYBLUE (-4525 700);
FORCEPROP 1 LAST WATTAGE 1/16W
J 0
(-4175 750);
DISPLAY 0.489362 (-4175 750);
PAINT SKYBLUE (-4175 750);
FORCEPROP 1 LAST TOLERANCE 5%
J 0
(-4150 825);
DISPLAY 0.489362 (-4150 825);
PAINT SKYBLUE (-4150 825);
FORCEPROP 1 LAST PACK_TYPE 0402LF
J 0
(-4175 700);
DISPLAY 0.489362 (-4175 700);
PAINT SKYBLUE (-4175 700);
FORCEPROP 2 LAST CDS_LIB pure_quanta
J 0
(-4275 800);
DISPLAY INVISIBLE (-4275 800);
FORCEPROP 1 LAST PATH I85
J 0
(-4325 950);
DISPLAY 0.978723 (-4325 950);
PAINT WHITE (-4325 950);
DISPLAY INVISIBLE (-4325 950);
FORCEPROP 1 LAST PART_NUMBER CS00002JB13
J 0
(-4525 750);
DISPLAY 0.489362 (-4525 750);
PAINT SKYBLUE (-4525 750);
DISPLAY INVISIBLE (-4525 750);
FORCEADD ISL99390FRZTR5935..1
(-6025 1975);
FORCEPROP 1 LAST LOCATION PU31
J 0
(-6325 2850);
DISPLAY 0.489362 (-6325 2850);
PAINT SKYBLUE (-6325 2850);
FORCEPROP 2 LAST $SEC 1
J 0
(-6325 3000);
DISPLAY 0.680851 (-6325 3000);
PAINT MONO (-6325 3000);
DISPLAY INVISIBLE (-6325 3000);
FORCEPROP 2 LAST CDS_SEC 1
J 0
(-6325 3000);
DISPLAY 1.021277 (-6325 3000);
DISPLAY INVISIBLE (-6325 3000);
FORCEPROP 2 LASTPIN (-5625 1525) $PN 2
J 0
(-5615 1535);
DISPLAY 0.489362 (-5615 1535);
PAINT MONO (-5615 1535);
FORCEPROP 2 LASTPIN (-5625 2325) $PN 33
J 0
(-5615 2335);
DISPLAY 0.489362 (-5615 2335);
PAINT MONO (-5615 2335);
FORCEPROP 2 LASTPIN (-6475 1725) $PN 31
J 2
(-6485 1735);
DISPLAY 0.489362 (-6485 1735);
PAINT MONO (-6485 1735);
FORCEPROP 2 LASTPIN (-6475 2125) $PN 35
J 2
(-6485 2135);
DISPLAY 0.489362 (-6485 2135);
PAINT MONO (-6485 2135);
FORCEPROP 2 LASTPIN (-5625 1675) $PN 6
J 0
(-5615 1685);
DISPLAY 0.489362 (-5615 1685);
PAINT MONO (-5615 1685);
FORCEPROP 2 LASTPIN (-5625 1625) $PN 41
J 0
(-5615 1635);
DISPLAY 0.489362 (-5615 1635);
PAINT MONO (-5615 1635);
FORCEPROP 2 LASTPIN (-6475 1975) $PN 38
J 2
(-6485 1985);
DISPLAY 0.489362 (-6485 1985);
PAINT MONO (-6485 1985);
FORCEPROP 2 LASTPIN (-6475 1675) $PN 37
J 2
(-6485 1685);
DISPLAY 0.489362 (-6485 1685);
PAINT MONO (-6485 1685);
FORCEPROP 2 LASTPIN (-5625 1475) $PN 5
J 0
(-5615 1485);
DISPLAY 0.489362 (-5615 1485);
PAINT MONO (-5615 1485);
FORCEPROP 2 LASTPIN (-5625 1425) $PN 7_9-20_24
J 0
(-5615 1435);
DISPLAY 0.489362 (-5615 1435);
PAINT MONO (-5615 1435);
FORCEPROP 2 LASTPIN (-5625 1375) $PN 40
J 0
(-5615 1385);
DISPLAY 0.489362 (-5615 1385);
PAINT MONO (-5615 1385);
FORCEPROP 2 LASTPIN (-5625 2075) $PN 32
J 0
(-5615 2085);
DISPLAY 0.489362 (-5615 2085);
PAINT MONO (-5615 2085);
FORCEPROP 2 LASTPIN (-6475 2625) $PN 4
J 2
(-6485 2635);
DISPLAY 0.489362 (-6485 2635);
PAINT MONO (-6485 2635);
FORCEPROP 2 LASTPIN (-6475 1375) $PN 34
J 2
(-6485 1385);
DISPLAY 0.489362 (-6485 1385);
PAINT MONO (-6485 1385);
FORCEPROP 2 LASTPIN (-6475 1875) $PN 39
J 2
(-6485 1885);
DISPLAY 0.489362 (-6485 1885);
PAINT MONO (-6485 1885);
FORCEPROP 2 LASTPIN (-5625 1975) $PN 10_19
J 0
(-5615 1985);
DISPLAY 0.489362 (-5615 1985);
PAINT MONO (-5615 1985);
FORCEPROP 2 LASTPIN (-6475 1475) $PN 36
J 2
(-6485 1485);
DISPLAY 0.489362 (-6485 1485);
PAINT MONO (-6485 1485);
FORCEPROP 2 LASTPIN (-6475 2325) $PN 3
J 2
(-6485 2335);
DISPLAY 0.489362 (-6485 2335);
PAINT MONO (-6485 2335);
FORCEPROP 2 LASTPIN (-5625 2625) $PN 25_29
J 0
(-5615 2635);
DISPLAY 0.489362 (-5615 2635);
PAINT MONO (-5615 2635);
FORCEPROP 2 LASTPIN (-5625 2575) $PN 30
J 0
(-5615 2585);
DISPLAY 0.489362 (-5615 2585);
PAINT MONO (-5615 2585);
FORCEPROP 2 LASTPIN (-5625 1725) $PN 1
J 0
(-5615 1735);
DISPLAY 0.489362 (-5615 1735);
PAINT MONO (-5615 1735);
FORCEPROP 2 LAST PART_TYPE SMLF
J 0
(-6325 2950);
DISPLAY 1.021277 (-6325 2950);
FORCEPROP 2 LAST VALUE ISL99390FRZ-TR5935
J 0
(-6325 2900);
DISPLAY 0.489362 (-6325 2900);
PAINT SKYBLUE (-6325 2900);
FORCEPROP 1 LAST MATERIAL IC
J 0
(-6325 2700);
DISPLAY 0.489362 (-6325 2700);
PAINT SKYBLUE (-6325 2700);
FORCEPROP 2 LAST CDS_LIB pure_quanta
J 0
(-6025 1975);
DISPLAY INVISIBLE (-6025 1975);
FORCEPROP 1 LAST CDS_LMAN_SYM_OUTLINE -300,700,250,-650
J 0
(-6025 1975);
DISPLAY 0.468085 (-6025 1975);
PAINT GREEN (-6025 1975);
DISPLAY INVISIBLE (-6025 1975);
FORCEPROP 1 LAST NEEDS_NO_SIZE TRUE
J 0
(-6025 1975);
DISPLAY 0.723404 (-6025 1975);
PAINT GREEN (-6025 1975);
DISPLAY INVISIBLE (-6025 1975);
FORCEPROP 1 LAST PATH I86
J 0
(-6025 1975);
DISPLAY 0.723404 (-6025 1975);
PAINT GREEN (-6025 1975);
DISPLAY INVISIBLE (-6025 1975);
FORCEPROP 1 LAST PART_NUMBER AL099390004
J 0
(-6325 2775);
DISPLAY 0.489362 (-6325 2775);
PAINT SKYBLUE (-6325 2775);
DISPLAY INVISIBLE (-6325 2775);
FORCEADD Q_CAP..1
(-3750 5600);
FORCEPROP 1 LAST LOCATION PC8011
J 0
(-3700 5700);
DISPLAY 0.489362 (-3700 5700);
PAINT SKYBLUE (-3700 5700);
FORCEPROP 0 LAST $SEC 1
J 0
(-3700 5725);
DISPLAY 0.680851 (-3700 5725);
PAINT MONO (-3700 5725);
DISPLAY INVISIBLE (-3700 5725);
FORCEPROP 0 LAST CDS_SEC 1
J 0
(-3700 5725);
DISPLAY 0.680851 (-3700 5725);
DISPLAY INVISIBLE (-3700 5725);
FORCEPROP 1 LASTPIN (-3750 5700) $PN 1
J 0
(-3740 5680);
DISPLAY 0.787234 (-3740 5680);
PAINT MONO (-3740 5680);
FORCEPROP 1 LASTPIN (-3750 5500) $PN 2
J 0
(-3740 5480);
DISPLAY 0.787234 (-3740 5480);
PAINT MONO (-3740 5480);
FORCEPROP 1 LAST TOLERANCE 20%
J 0
(-3700 5550);
DISPLAY 0.489362 (-3700 5550);
PAINT SKYBLUE (-3700 5550);
FORCEPROP 1 LAST VALUE 22UF
J 0
(-3700 5650);
DISPLAY 0.489362 (-3700 5650);
PAINT SKYBLUE (-3700 5650);
FORCEPROP 1 LAST MATERIAL X6S
J 0
(-3700 5500);
DISPLAY 0.489362 (-3700 5500);
PAINT SKYBLUE (-3700 5500);
FORCEPROP 1 LAST VOLTAGE 16V
J 0
(-3700 5600);
DISPLAY 0.489362 (-3700 5600);
PAINT SKYBLUE (-3700 5600);
FORCEPROP 1 LAST PACK_TYPE C0805
J 0
(-3700 5400);
DISPLAY 0.489362 (-3700 5400);
PAINT SKYBLUE (-3700 5400);
FORCEPROP 2 LAST CDS_LIB pure_quanta
J 0
(-3750 5600);
DISPLAY INVISIBLE (-3750 5600);
FORCEPROP 1 LAST PATH I87
J 0
(-3700 5750);
DISPLAY 0.978723 (-3700 5750);
PAINT WHITE (-3700 5750);
DISPLAY INVISIBLE (-3700 5750);
FORCEPROP 1 LAST PART_NUMBER CH6223MEA01
J 0
(-3700 5450);
DISPLAY 0.489362 (-3700 5450);
PAINT SKYBLUE (-3700 5450);
DISPLAY INVISIBLE (-3700 5450);
FORCEADD Q_CAP..1
(-3375 2850);
FORCEPROP 1 LAST LOCATION PC8012
J 0
(-3325 2950);
DISPLAY 0.489362 (-3325 2950);
PAINT SKYBLUE (-3325 2950);
FORCEPROP 0 LAST $SEC 1
J 0
(-3325 2975);
DISPLAY 0.680851 (-3325 2975);
PAINT MONO (-3325 2975);
DISPLAY INVISIBLE (-3325 2975);
FORCEPROP 0 LAST CDS_SEC 1
J 0
(-3325 2975);
DISPLAY 0.680851 (-3325 2975);
DISPLAY INVISIBLE (-3325 2975);
FORCEPROP 1 LASTPIN (-3375 2950) $PN 1
J 0
(-3365 2930);
DISPLAY 0.787234 (-3365 2930);
PAINT MONO (-3365 2930);
FORCEPROP 1 LASTPIN (-3375 2750) $PN 2
J 0
(-3365 2730);
DISPLAY 0.787234 (-3365 2730);
PAINT MONO (-3365 2730);
FORCEPROP 1 LAST PACK_TYPE C0805
J 0
(-3325 2650);
DISPLAY 0.489362 (-3325 2650);
PAINT SKYBLUE (-3325 2650);
FORCEPROP 1 LAST MATERIAL X6S
J 0
(-3325 2750);
DISPLAY 0.489362 (-3325 2750);
PAINT SKYBLUE (-3325 2750);
FORCEPROP 1 LAST VOLTAGE 16V
J 0
(-3325 2850);
DISPLAY 0.489362 (-3325 2850);
PAINT SKYBLUE (-3325 2850);
FORCEPROP 1 LAST TOLERANCE 20%
J 0
(-3325 2800);
DISPLAY 0.489362 (-3325 2800);
PAINT SKYBLUE (-3325 2800);
FORCEPROP 1 LAST VALUE 22UF
J 0
(-3325 2900);
DISPLAY 0.489362 (-3325 2900);
PAINT SKYBLUE (-3325 2900);
FORCEPROP 2 LAST CDS_LIB pure_quanta
J 0
(-3375 2850);
DISPLAY INVISIBLE (-3375 2850);
FORCEPROP 1 LAST PATH I88
J 0
(-3325 3000);
DISPLAY 0.978723 (-3325 3000);
PAINT WHITE (-3325 3000);
DISPLAY INVISIBLE (-3325 3000);
FORCEPROP 1 LAST PART_NUMBER CH6223MEA01
J 0
(-3325 2700);
DISPLAY 0.489362 (-3325 2700);
PAINT SKYBLUE (-3325 2700);
DISPLAY INVISIBLE (-3325 2700);
FORCEADD OFFPAGE..2
R 2
(-7175 1975);
FORCEPROP 2 LAST $XR0 210 
J 0
(-7430 1975);
DISPLAY 0.638298 (-7430 1975);
PAINT MONO (-7430 1975);
FORCEPROP 2 LAST CDS_LIB standard
J 2
(-7175 1975);
DISPLAY INVISIBLE (-7175 1975);
FORCEPROP 1 LAST OFFPAGE TRUE
J 2
(-7500 1850);
DISPLAY 0.872340 (-7500 1850);
PAINT GREEN (-7500 1850);
DISPLAY INVISIBLE (-7500 1850);
FORCEPROP 1 LAST COMMENT_BODY TRUE
J 2
(-7130 1880);
DISPLAY 0.872340 (-7130 1880);
PAINT GREEN (-7130 1880);
DISPLAY INVISIBLE (-7130 1880);
FORCEPROP 2 LAST PATH I9
J 0
(-7450 2025);
DISPLAY 0.680851 (-7450 2025);
DISPLAY INVISIBLE (-7450 2025);
FORCEADD DNS..1
(-7175 1650);
PAINT RED (-7175 1650);
FORCEPROP 2 LAST CDS_LIB mstr_misc
J 0
(-7175 1650);
DISPLAY INVISIBLE (-7175 1650);
FORCEPROP 1 LAST COMMENT_BODY TRUE
R 1
J 0
(-7100 1425);
DISPLAY 0.872340 (-7100 1425);
PAINT GREEN (-7100 1425);
DISPLAY INVISIBLE (-7100 1425);
FORCEADD DNS..1
(-4650 1225);
PAINT RED (-4650 1225);
FORCEPROP 2 LAST CDS_LIB mstr_misc
J 0
(-4650 1225);
DISPLAY INVISIBLE (-4650 1225);
FORCEPROP 1 LAST COMMENT_BODY TRUE
R 1
J 0
(-4575 1000);
DISPLAY 0.872340 (-4575 1000);
PAINT GREEN (-4575 1000);
DISPLAY INVISIBLE (-4575 1000);
FORCEADD DNS..1
(-4650 1775);
PAINT RED (-4650 1775);
FORCEPROP 2 LAST CDS_LIB mstr_misc
J 0
(-4650 1775);
DISPLAY INVISIBLE (-4650 1775);
FORCEPROP 1 LAST COMMENT_BODY TRUE
R 1
J 0
(-4575 1550);
DISPLAY 0.872340 (-4575 1550);
PAINT GREEN (-4575 1550);
DISPLAY INVISIBLE (-4575 1550);
FORCEADD DNS..1
(-4725 4050);
PAINT RED (-4725 4050);
FORCEPROP 2 LAST CDS_LIB mstr_misc
J 0
(-4725 4050);
DISPLAY INVISIBLE (-4725 4050);
FORCEPROP 1 LAST COMMENT_BODY TRUE
R 1
J 0
(-4650 3825);
DISPLAY 0.872340 (-4650 3825);
PAINT GREEN (-4650 3825);
DISPLAY INVISIBLE (-4650 3825);
FORCEADD DNS..1
(-7200 4425);
PAINT RED (-7200 4425);
FORCEPROP 2 LAST CDS_LIB mstr_misc
J 0
(-7200 4425);
DISPLAY INVISIBLE (-7200 4425);
FORCEPROP 1 LAST COMMENT_BODY TRUE
R 1
J 0
(-7125 4200);
DISPLAY 0.872340 (-7125 4200);
PAINT GREEN (-7125 4200);
DISPLAY INVISIBLE (-7125 4200);
FORCEADD DNS..1
(-4725 4550);
PAINT RED (-4725 4550);
FORCEPROP 2 LAST CDS_LIB mstr_misc
J 0
(-4725 4550);
DISPLAY INVISIBLE (-4725 4550);
FORCEPROP 1 LAST COMMENT_BODY TRUE
R 1
J 0
(-4650 4325);
DISPLAY 0.872340 (-4650 4325);
PAINT GREEN (-4650 4325);
DISPLAY INVISIBLE (-4650 4325);
FORCEADD DNS..1
(-1775 3050);
PAINT RED (-1775 3050);
FORCEPROP 2 LAST CDS_LIB mstr_misc
J 0
(-1775 3050);
DISPLAY INVISIBLE (-1775 3050);
FORCEPROP 1 LAST COMMENT_BODY TRUE
R 1
J 0
(-1700 2825);
DISPLAY 0.872340 (-1700 2825);
PAINT GREEN (-1700 2825);
DISPLAY INVISIBLE (-1700 2825);
FORCEADD QUANTA_TITLE_BLOCK_C..1
(-425 -150);
FORCEPROP 0 LAST CDS_CON_LAST_MODIFIED Thu Sep 14 16:12:21 2023
J 0
(-2310 -135);
DISPLAY INVISIBLE (-2310 -135);
FORCEPROP 1 LAST CUSTOM_TXT_CDS <CON_LAST_MODIFIED>
J 0
(-2310 -135);
DISPLAY 0.978723 (-2310 -135);
FORCEPROP 2 LAST CUSTOM_TXT_CDS <XR_PAGE_TITLE>
J 0
(-8315 5100);
DISPLAY 0.638298 (-8315 5100);
PAINT PINK (-8315 5100);
DISPLAY INVISIBLE (-8315 5100);
FORCEPROP 1 LAST CUSTOM_TXT_CDS <NAME_2>
J 0
(-3600 -100);
FORCEPROP 1 LAST CUSTOM_TXT_CDS <NAME_1>
J 0
(-3600 25);
FORCEPROP 1 LAST CUSTOM_TXT_CDS <Q_NUMBER>
J 0
(-1828 -47);
DISPLAY 1.212766 (-1828 -47);
FORCEPROP 1 LAST CUSTOM_TXT_CDS <Q_PROJ>
J 0
(-2807 -48);
DISPLAY 1.212766 (-2807 -48);
FORCEPROP 1 LAST CUSTOM_TXT_CDS <Q_REV>
J 0
(-609 -47);
DISPLAY 1.212766 (-609 -47);
FORCEPROP 1 LAST CUSTOM_TXT_CDS <CON_PAGE_NUM> OF <CON_TOTAL_PAGES>
J 0
(-871 -132);
DISPLAY 0.978723 (-871 -132);
FORCEPROP 1 LAST Q_TITLE PVDDCR_SOC_P1 VR PHASE 1&2
J 0
(-9725 -100);
DISPLAY 2.446809 (-9725 -100);
PAINT GREEN (-9725 -100);
FORCEPROP 2 LAST CDS_LIB pure_quanta
J 0
(-425 -150);
DISPLAY INVISIBLE (-425 -150);
FORCEPROP 1 LAST CDS_LMAN_SYM_OUTLINE -9475,6775,100,-125
J 0
(-425 -150);
DISPLAY 0.468085 (-425 -150);
PAINT GREEN (-425 -150);
DISPLAY INVISIBLE (-425 -150);
FORCEPROP 2 LAST PAGE_BORDER TRUE
J 0
(-8315 5100);
DISPLAY 0.638298 (-8315 5100);
PAINT PINK (-8315 5100);
DISPLAY INVISIBLE (-8315 5100);
FORCEPROP 2 LAST CDS_XR_PAGE_TITLE CR-215 : @T6G_MB_LIB.T6G(SCH_1):PAGE215
J 0
(-8315 5100);
DISPLAY 0.638298 (-8315 5100);
PAINT PINK (-8315 5100);
DISPLAY INVISIBLE (-8315 5100);
FORCEPROP 1 LAST Q_DEPT BU9
J 1
(-4188 -101);
DISPLAY 1.957447 (-4188 -101);
PAINT GREEN (-4188 -101);
DISPLAY INVISIBLE (-4188 -101);
FORCEPROP 1 LAST COMMENT_BODY TRUE
J 0
(-413 -163);
DISPLAY 0.978723 (-413 -163);
PAINT GREEN (-413 -163);
DISPLAY INVISIBLE (-413 -163);
WIRE 16 -1 (-7525 2225)(-7525 2175);
WIRE 16 -1 (-7175 2800)(-7175 2675);
WIRE 16 -1 (-4625 1125)(-4625 1050);
WIRE 16 -1 (-4700 3950)(-4700 3875);
WIRE 16 -1 (-7850 1600)(-7850 1475);
WIRE 16 -1 (-7875 4375)(-7875 4250);
WIRE 16 -1 (-7300 4450)(-7550 4450);
WIRE 16 -1 (-7550 4450)(-7550 4325);
WIRE 16 -1 (-7550 5000)(-7550 4950);
WIRE 16 -1 (-7200 5575)(-7200 5450);
WIRE 16 -1 (-7275 1675)(-7525 1675);
WIRE 16 -1 (-7525 1675)(-7525 1550);
WIRE 16 -1 (-2625 5525)(-2625 5375);
WIRE 16 -1 (-8025 1875)(-7850 1875);
WIRE 16 -1 (-6475 1875)(-7850 1875);
FORCEPROP 2 LAST SIG_NAME PVDDCR_CPU0_P1_VCCS
J 2
(-6535 1885);
DISPLAY 0.489362 (-6535 1885);
WIRE 16 -1 (-7850 1800)(-7850 1875);
WIRE 16 -1 (-6475 1975)(-7125 1975);
FORCEPROP 2 LAST SIG_NAME PVDDCR_SOC_P1_IMON2
J 2
(-6535 1985);
DISPLAY 0.489362 (-6535 1985);
WIRE 16 -1 (-7525 2500)(-7025 2500);
WIRE 16 -1 (-7525 2775)(-7525 2500);
WIRE 16 -1 (-7525 2500)(-7525 2425);
WIRE 16 -1 (-7025 2500)(-7025 2325);
FORCEPROP 2 LAST SIG_NAME PVDDCR_SOC_P1_VCC2
J 2
(-6560 2335);
DISPLAY 0.489362 (-6560 2335);
FORCEPROP 2 LASTPROP $XRERR UNIQUE?
J 0
(-6800 2335);
DISPLAY 0.638298 (-6800 2335);
PAINT MONO (-6800 2335);
DISPLAY INVISIBLE (-6800 2335);
WIRE 16 -1 (-7025 2325)(-6475 2325);
WIRE 16 -1 (-7025 2325)(-7025 2125);
WIRE 16 -1 (-7025 2125)(-6475 2125);
WIRE 16 -1 (-3375 2750)(-3375 2650);
WIRE 16 -1 (-3375 2650)(-3725 2650);
WIRE 16 -1 (-3725 2650)(-4050 2650);
WIRE 16 -1 (-3725 2650)(-3725 2600);
WIRE 16 -1 (-3725 2775)(-3725 2650);
WIRE 16 -1 (-4050 2775)(-4050 2650);
WIRE 16 -1 (-4050 2650)(-4350 2650);
WIRE 16 -1 (-4350 2775)(-4350 2650);
WIRE 16 -1 (-4675 2650)(-4350 2650);
WIRE 16 -1 (-4675 2775)(-4675 2650);
WIRE 16 -1 (-5000 2650)(-4675 2650);
WIRE 16 -1 (-5000 2775)(-5000 2650);
WIRE 16 -1 (-5375 2650)(-5000 2650);
WIRE 16 -1 (-5375 2775)(-5375 2650);
WIRE 16 -1 (-5525 3050)(-5525 2625);
WIRE 16 -1 (-5525 3050)(-5375 3050);
WIRE 16 -1 (-5525 2625)(-5525 2575);
WIRE 16 -1 (-5625 2625)(-5525 2625);
WIRE 16 -1 (-5525 2575)(-5625 2575);
WIRE 16 -1 (-5375 3050)(-5000 3050);
WIRE 16 -1 (-5375 3050)(-5375 2975);
WIRE 16 -1 (-5000 3050)(-4675 3050);
WIRE 16 -1 (-5000 2975)(-5000 3050);
WIRE 16 -1 (-4675 3050)(-4350 3050);
WIRE 16 -1 (-4675 2975)(-4675 3050);
WIRE 16 -1 (-4350 3050)(-4050 3050);
WIRE 16 -1 (-4350 3050)(-4350 2975);
WIRE 16 -1 (-3725 3050)(-4050 3050);
WIRE 16 -1 (-4050 3050)(-4050 2975);
WIRE 16 -1 (-3725 3125)(-3725 3050);
WIRE 16 -1 (-3725 3050)(-3375 3050);
WIRE 16 -1 (-3725 3050)(-3725 2975);
WIRE 16 -1 (-3375 3050)(-3375 2950);
WIRE 16 -1 (-5650 4500)(-4925 4500);
WIRE 16 -1 (-4925 4500)(-4925 3725);
WIRE 16 -1 (-4325 3725)(-4925 3725);
FORCEPROP 2 LAST SIG_NAME PVDDCR_SOC_P1_VOS1
J 0
(-5560 4525);
DISPLAY 0.489362 (-5560 4525);
FORCEPROP 2 LASTPROP $XRERR UNIQUE?
J 0
(-5800 4525);
DISPLAY 0.638298 (-5800 4525);
PAINT MONO (-5800 4525);
DISPLAY INVISIBLE (-5800 4525);
WIRE 16 -1 (-5650 4750)(-4700 4750);
FORCEPROP 2 LAST SIG_NAME SW_PVDDCR_SOC_P1_SW1
J 0
(-5560 4760);
DISPLAY 0.489362 (-5560 4760);
FORCEPROP 2 LASTPROP $XRERR UNIQUE?
J 0
(-5800 4760);
DISPLAY 0.638298 (-5800 4760);
PAINT MONO (-5800 4760);
DISPLAY INVISIBLE (-5800 4760);
WIRE 16 -1 (-4700 4750)(-3600 4750);
WIRE 16 -1 (-4700 4650)(-4700 4750);
WIRE 16 -1 (-3950 4875)(-3950 4850);
WIRE 16 -1 (-3950 4850)(-5650 4850);
FORCEPROP 2 LAST SIG_NAME SW_PVDDCR_SOC_P1_PH1
J 0
(-5560 4860);
DISPLAY 0.489362 (-5560 4860);
FORCEPROP 2 LASTPROP $XRERR UNIQUE?
J 0
(-5800 4860);
DISPLAY 0.638298 (-5800 4860);
PAINT MONO (-5800 4860);
DISPLAY INVISIBLE (-5800 4860);
WIRE 16 -1 (-5650 5100)(-4900 5100);
FORCEPROP 2 LAST SIG_NAME SW_PVDDCR_SOC_P1_BOOT1
J 0
(-5560 5110);
DISPLAY 0.489362 (-5560 5110);
FORCEPROP 2 LASTPROP $XRERR UNIQUE?
J 0
(-5800 5110);
DISPLAY 0.638298 (-5800 5110);
PAINT MONO (-5800 5110);
DISPLAY INVISIBLE (-5800 5110);
WIRE 16 -1 (-3950 5100)(-3950 5075);
WIRE 16 -1 (-4700 5100)(-3950 5100);
FORCEPROP 2 LAST SIG_NAME SW_PVDDCR_SOC_P1_BOOT1_RC
J 2
(-3985 5110);
DISPLAY 0.489362 (-3985 5110);
FORCEPROP 2 LASTPROP $XRERR UNIQUE?
J 0
(-4225 5110);
DISPLAY 0.638298 (-4225 5110);
PAINT MONO (-4225 5110);
DISPLAY INVISIBLE (-4225 5110);
WIRE 16 -1 (-7550 5275)(-7075 5275);
WIRE 16 -1 (-7550 5550)(-7550 5275);
WIRE 16 -1 (-7550 5275)(-7550 5200);
WIRE 16 -1 (-7075 5275)(-7075 5100);
FORCEPROP 2 LAST SIG_NAME PVDDCR_SOC_P1_VCC1
J 2
(-6585 5110);
DISPLAY 0.489362 (-6585 5110);
FORCEPROP 2 LASTPROP $XRERR UNIQUE?
J 0
(-6825 5110);
DISPLAY 0.638298 (-6825 5110);
PAINT MONO (-6825 5110);
DISPLAY INVISIBLE (-6825 5110);
WIRE 16 -1 (-7075 5100)(-6500 5100);
WIRE 16 -1 (-7075 5100)(-7075 4900);
WIRE 16 -1 (-7075 4900)(-6500 4900);
WIRE 16 -1 (-5625 2325)(-4800 2325);
FORCEPROP 2 LAST SIG_NAME SW_PVDDCR_SOC_P1_BOOT2
J 0
(-5510 2335);
DISPLAY 0.489362 (-5510 2335);
FORCEPROP 2 LASTPROP $XRERR UNIQUE?
J 0
(-5750 2335);
DISPLAY 0.638298 (-5750 2335);
PAINT MONO (-5750 2335);
DISPLAY INVISIBLE (-5750 2335);
WIRE 16 -1 (-3825 2325)(-3825 2300);
WIRE 16 -1 (-4600 2325)(-3825 2325);
FORCEPROP 2 LAST SIG_NAME SW_PVDDCR_SOC_P1_BOOT2_RC
J 2
(-3860 2335);
DISPLAY 0.489362 (-3860 2335);
FORCEPROP 2 LASTPROP $XRERR UNIQUE?
J 0
(-4100 2335);
DISPLAY 0.638298 (-4100 2335);
PAINT MONO (-4100 2335);
DISPLAY INVISIBLE (-4100 2335);
WIRE 17 273 (-925 2500)(-925 3575);
WIRE 17 273 (-925 2500)(-2525 2500);
WIRE 17 273 (-2525 3575)(-925 3575);
WIRE 17 273 (-2525 2500)(-2525 3575);
WIRE 16 -1 (-4125 3725)(-2050 3725);
WIRE 16 -1 (-2050 4750)(-2050 3725);
WIRE 16 -1 (-2050 4750)(-1975 4750);
WIRE 16 -1 (-2800 4750)(-2050 4750);
WIRE 16 -1 (-1575 4750)(-1975 4750);
WIRE 16 -1 (-1975 4650)(-1975 4750);
WIRE 16 -1 (-1150 4750)(-1575 4750);
WIRE 16 -1 (-1575 4750)(-1575 4675);
WIRE 16 -1 (-875 4750)(-1150 4750);
WIRE 16 -1 (-1150 4750)(-1150 4675);
WIRE 16 -1 (-875 4825)(-875 4750);
WIRE 16 -1 (-875 4750)(-875 4650);
WIRE 16 -1 (-2325 4425)(-2325 4500);
WIRE 16 -1 (-2325 4500)(-2800 4500);
WIRE 16 -1 (-3450 5500)(-3450 5375);
WIRE 16 -1 (-3450 5375)(-3750 5375);
WIRE 16 -1 (-3750 5500)(-3750 5375);
WIRE 16 -1 (-3750 5375)(-3925 5375);
WIRE 16 -1 (-3925 5325)(-3925 5375);
WIRE 16 -1 (-3950 5375)(-3925 5375);
WIRE 16 -1 (-3950 5375)(-3950 5500);
WIRE 16 -1 (-4175 5375)(-3950 5375);
WIRE 16 -1 (-4175 5500)(-4175 5375);
WIRE 16 -1 (-4175 5375)(-4475 5375);
WIRE 16 -1 (-4475 5500)(-4475 5375);
WIRE 16 -1 (-4800 5375)(-4475 5375);
WIRE 16 -1 (-4800 5500)(-4800 5375);
WIRE 16 -1 (-5125 5375)(-4800 5375);
WIRE 16 -1 (-5125 5500)(-5125 5375);
WIRE 16 -1 (-5450 5375)(-5125 5375);
WIRE 16 -1 (-5450 5500)(-5450 5375);
WIRE 16 -1 (-3450 5700)(-3450 5775);
WIRE 16 -1 (-3175 5775)(-3450 5775);
WIRE 16 -1 (-3450 5775)(-3750 5775);
WIRE 16 -1 (-3750 5775)(-3750 5700);
WIRE 16 -1 (-3750 5775)(-3925 5775);
WIRE 16 -1 (-3925 5825)(-3925 5775);
WIRE 16 -1 (-3950 5775)(-3925 5775);
WIRE 16 -1 (-3950 5700)(-3950 5775);
WIRE 16 -1 (-4175 5775)(-3950 5775);
WIRE 16 -1 (-4175 5775)(-4175 5700);
WIRE 16 -1 (-4475 5775)(-4175 5775);
WIRE 16 -1 (-4475 5775)(-4475 5700);
WIRE 16 -1 (-4800 5775)(-4475 5775);
WIRE 16 -1 (-4800 5700)(-4800 5775);
WIRE 16 -1 (-5125 5775)(-4800 5775);
WIRE 16 -1 (-5125 5700)(-5125 5775);
WIRE 16 -1 (-5450 5775)(-5125 5775);
WIRE 16 -1 (-5450 5700)(-5450 5775);
WIRE 16 -1 (-5550 5775)(-5450 5775);
WIRE 16 -1 (-5550 5775)(-5550 5400);
WIRE 16 -1 (-5550 5400)(-5550 5350);
WIRE 16 -1 (-5650 5400)(-5550 5400);
WIRE 16 -1 (-5550 5350)(-5650 5350);
WIRE 16 -1 (-875 4450)(-875 4350);
WIRE 16 -1 (-875 4225)(-875 4350);
WIRE 16 -1 (-875 4350)(-1150 4350);
WIRE 16 -1 (-1150 4475)(-1150 4350);
WIRE 16 -1 (-1150 4350)(-1575 4350);
WIRE 16 -1 (-1575 4475)(-1575 4350);
WIRE 16 -1 (-1975 4350)(-1575 4350);
WIRE 16 -1 (-1975 4350)(-1975 4450);
WIRE 16 -1 (-2575 5775)(-2625 5775);
WIRE 16 -1 (-2575 5825)(-2575 5775);
WIRE 16 -1 (-2625 5725)(-2625 5775);
WIRE 16 -1 (-2625 5775)(-2975 5775);
WIRE 16 -1 (-1775 3175)(-1775 3275);
WIRE 16 -1 (-1450 3275)(-1775 3275);
WIRE 16 -1 (-2125 3275)(-1775 3275);
WIRE 16 -1 (-2125 3175)(-2125 3275);
WIRE 16 -1 (-1450 3275)(-1450 3300);
WIRE 16 -1 (-1450 3175)(-1450 3275);
WIRE 16 -1 (-1450 2975)(-1450 2825);
WIRE 16 -1 (-1450 2775)(-1450 2825);
WIRE 16 -1 (-1450 2825)(-1775 2825);
WIRE 16 -1 (-1775 2975)(-1775 2825);
WIRE 16 -1 (-1775 2825)(-2125 2825);
WIRE 16 -1 (-2125 2975)(-2125 2825);
WIRE 16 -1 (-1900 1975)(-1700 1975);
WIRE 16 -1 (-1900 1975)(-1900 800);
WIRE 16 -1 (-2550 1975)(-1900 1975);
WIRE 16 -1 (-1700 1975)(-1275 1975);
WIRE 16 -1 (-1700 1975)(-1700 1900);
WIRE 16 -1 (-1275 2075)(-1275 1975);
WIRE 16 -1 (-1275 1975)(-1275 1900);
WIRE 16 -1 (-1900 800)(-4175 800);
WIRE 16 -1 (-1275 1700)(-1275 1575);
WIRE 16 -1 (-1275 1500)(-1275 1575);
WIRE 16 -1 (-1275 1575)(-1700 1575);
WIRE 16 -1 (-1700 1700)(-1700 1575);
WIRE 16 -1 (-7550 5750)(-7550 5875);
WIRE 16 -1 (-7200 5875)(-7550 5875);
WIRE 16 -1 (-7550 6000)(-7550 5875);
WIRE 16 -1 (-6875 5875)(-7200 5875);
WIRE 16 -1 (-7200 5775)(-7200 5875);
WIRE 16 -1 (-6875 5400)(-6875 5875);
WIRE 16 -1 (-6875 5400)(-6500 5400);
WIRE 16 -1 (-5475 4150)(-5475 4200);
WIRE 16 -1 (-5650 4150)(-5475 4150);
WIRE 16 -1 (-5475 4075)(-5475 4150);
WIRE 16 -1 (-5475 4200)(-5475 4250);
WIRE 16 -1 (-5650 4200)(-5475 4200);
WIRE 16 -1 (-5475 4300)(-5475 4250);
WIRE 16 -1 (-5650 4250)(-5475 4250);
WIRE 16 -1 (-5475 4300)(-5650 4300);
WIRE 16 -1 (-5625 1375)(-5450 1375);
WIRE 16 -1 (-5450 1375)(-5450 1425);
WIRE 16 -1 (-5450 1325)(-5450 1375);
WIRE 16 -1 (-5450 1425)(-5450 1475);
WIRE 16 -1 (-5625 1425)(-5450 1425);
WIRE 16 -1 (-5450 1525)(-5450 1475);
WIRE 16 -1 (-5625 1475)(-5450 1475);
WIRE 16 -1 (-5450 1525)(-5625 1525);
WIRE 16 -1 (-7525 2975)(-7525 3100);
WIRE 16 -1 (-7175 3100)(-7525 3100);
WIRE 16 -1 (-7525 3225)(-7525 3100);
WIRE 16 -1 (-6850 3100)(-7175 3100);
WIRE 16 -1 (-7175 3000)(-7175 3100);
WIRE 16 -1 (-6850 2625)(-6850 3100);
WIRE 16 -1 (-6850 2625)(-6475 2625);
WIRE 16 -1 (-6500 4150)(-7100 4150);
FORCEPROP 2 LAST SIG_NAME PVDDCR_SOC_P1_PWM1
J 2
(-6560 4160);
DISPLAY 0.489362 (-6560 4160);
WIRE 16 -1 (-5650 4450)(-5125 4450);
FORCEPROP 2 LAST SIG_NAME NC_PVDDCR_SOC_P1_GL1_1
J 0
(-5560 4460);
DISPLAY 0.489362 (-5560 4460);
FORCEPROP 2 LASTPROP $XRERR UNIQUE?
J 0
(-5095 4450);
DISPLAY 0.638298 (-5095 4450);
PAINT MONO (-5095 4450);
DISPLAY INVISIBLE (-5095 4450);
WIRE 16 -1 (-5625 1975)(-4625 1975);
FORCEPROP 2 LAST SIG_NAME SW_PVDDCR_SOC_P1_SW2
J 0
(-5510 1985);
DISPLAY 0.489362 (-5510 1985);
FORCEPROP 2 LASTPROP $XRERR UNIQUE?
J 0
(-5750 1985);
DISPLAY 0.638298 (-5750 1985);
PAINT MONO (-5750 1985);
DISPLAY INVISIBLE (-5750 1985);
WIRE 16 -1 (-4625 1975)(-3350 1975);
WIRE 16 -1 (-4625 1875)(-4625 1975);
WIRE 16 -1 (-3825 2100)(-3825 2075);
WIRE 16 -1 (-3825 2075)(-5625 2075);
FORCEPROP 2 LAST SIG_NAME SW_PVDDCR_SOC_P1_PH2
J 0
(-5510 2085);
DISPLAY 0.489362 (-5510 2085);
FORCEPROP 2 LASTPROP $XRERR UNIQUE?
J 0
(-5750 2085);
DISPLAY 0.638298 (-5750 2085);
PAINT MONO (-5750 2085);
DISPLAY INVISIBLE (-5750 2085);
WIRE 16 -1 (-4100 4500)(-3600 4500);
FORCEPROP 2 LAST SIG_NAME IND_SOC_P1_CPL2
J 0
(-4010 4510);
DISPLAY 0.489362 (-4010 4510);
WIRE 16 -1 (-6475 1375)(-7075 1375);
FORCEPROP 2 LAST SIG_NAME PVDDCR_SOC_P1_PWM2
J 2
(-6535 1385);
DISPLAY 0.489362 (-6535 1385);
WIRE 16 -1 (-4375 800)(-4875 800);
FORCEPROP 2 LAST SIG_NAME PVDDCR_SOC_P1_VOS2
J 0
(-5510 1750);
DISPLAY 0.489362 (-5510 1750);
FORCEPROP 2 LASTPROP $XRERR UNIQUE?
J 0
(-5750 1750);
DISPLAY 0.638298 (-5750 1750);
PAINT MONO (-5750 1750);
DISPLAY INVISIBLE (-5750 1750);
WIRE 16 -1 (-4875 800)(-4875 1725);
WIRE 16 -1 (-5625 1725)(-4875 1725);
WIRE 16 -1 (-2150 1725)(-2550 1725);
FORCEPROP 2 LAST SIG_NAME IND_SOC_P1_CPL2
J 0
(-2485 1735);
DISPLAY 0.489362 (-2485 1735);
WIRE 16 -1 (-3875 1725)(-3350 1725);
FORCEPROP 2 LAST SIG_NAME IND_SOC_P1_CPL3
J 0
(-3810 1735);
DISPLAY 0.489362 (-3810 1735);
WIRE 16 -1 (-4700 4450)(-4700 4150);
FORCEPROP 2 LAST SIG_NAME SW_PVDDCR_SOC_P1_SW1_RC
J 0
(-4660 4260);
DISPLAY 0.489362 (-4660 4260);
FORCEPROP 2 LASTPROP $XRERR UNIQUE?
J 0
(-4900 4260);
DISPLAY 0.638298 (-4900 4260);
PAINT MONO (-4900 4260);
DISPLAY INVISIBLE (-4900 4260);
WIRE 16 -1 (-5650 4400)(-5125 4400);
FORCEPROP 2 LAST SIG_NAME NC_PVDDCR_SOC_P1_GL2_1
J 0
(-5560 4410);
DISPLAY 0.489362 (-5560 4410);
FORCEPROP 2 LASTPROP $XRERR UNIQUE?
J 0
(-5095 4400);
DISPLAY 0.638298 (-5095 4400);
PAINT MONO (-5095 4400);
DISPLAY INVISIBLE (-5095 4400);
WIRE 16 -1 (-6500 4750)(-7150 4750);
FORCEPROP 2 LAST SIG_NAME PVDDCR_SOC_P1_IMON1
J 2
(-6560 4760);
DISPLAY 0.489362 (-6560 4760);
WIRE 16 -1 (-6500 4250)(-7125 4250);
FORCEPROP 2 LAST SIG_NAME PVDDCR_SOC_P1_TEMP1
J 2
(-6560 4260);
DISPLAY 0.489362 (-6560 4260);
WIRE 16 -1 (-7100 4450)(-6500 4450);
FORCEPROP 2 LAST SIG_NAME PVDDCR_SOC_P1_LSET1
J 2
(-6560 4460);
DISPLAY 0.489362 (-6560 4460);
FORCEPROP 2 LASTPROP $XRERR UNIQUE?
J 0
(-6800 4460);
DISPLAY 0.638298 (-6800 4460);
PAINT MONO (-6800 4460);
DISPLAY INVISIBLE (-6800 4460);
WIRE 16 -1 (-6500 4500)(-6950 4500);
FORCEPROP 2 LAST SIG_NAME NC_PVDDCR_SOC_P1_DNC1
J 2
(-6560 4510);
DISPLAY 0.489362 (-6560 4510);
FORCEPROP 2 LASTPROP $XRERR UNIQUE?
J 0
(-7190 4500);
DISPLAY 0.638298 (-7190 4500);
PAINT MONO (-7190 4500);
DISPLAY INVISIBLE (-7190 4500);
WIRE 16 -1 (-8050 4650)(-7875 4650);
WIRE 16 -1 (-6500 4650)(-7875 4650);
FORCEPROP 2 LAST SIG_NAME PVDDCR_CPU0_P1_VCCS
J 2
(-6560 4660);
DISPLAY 0.489362 (-6560 4660);
WIRE 16 -1 (-7875 4575)(-7875 4650);
WIRE 16 -1 (-4625 1675)(-4625 1325);
FORCEPROP 2 LAST SIG_NAME SW_PVDDCR_SOC_P1_SW2_RC
J 0
(-4585 1485);
DISPLAY 0.489362 (-4585 1485);
FORCEPROP 2 LASTPROP $XRERR UNIQUE?
J 0
(-4825 1485);
DISPLAY 0.638298 (-4825 1485);
PAINT MONO (-4825 1485);
DISPLAY INVISIBLE (-4825 1485);
WIRE 16 -1 (-5625 1675)(-5100 1675);
FORCEPROP 2 LAST SIG_NAME NC_PVDDCR_SOC_P1_GL1_2
J 0
(-5510 1685);
DISPLAY 0.489362 (-5510 1685);
FORCEPROP 2 LASTPROP $XRERR UNIQUE?
J 0
(-5070 1675);
DISPLAY 0.638298 (-5070 1675);
PAINT MONO (-5070 1675);
DISPLAY INVISIBLE (-5070 1675);
WIRE 16 -1 (-5625 1625)(-5100 1625);
FORCEPROP 2 LAST SIG_NAME NC_PVDDCR_SOC_P1_GL2_2
J 0
(-5510 1635);
DISPLAY 0.489362 (-5510 1635);
FORCEPROP 2 LASTPROP $XRERR UNIQUE?
J 0
(-5070 1625);
DISPLAY 0.638298 (-5070 1625);
PAINT MONO (-5070 1625);
DISPLAY INVISIBLE (-5070 1625);
WIRE 16 -1 (-6475 1725)(-6925 1725);
FORCEPROP 2 LAST SIG_NAME NC_PVDDCR_SOC_P1_DNC2
J 2
(-6535 1735);
DISPLAY 0.489362 (-6535 1735);
FORCEPROP 2 LASTPROP $XRERR UNIQUE?
J 0
(-7165 1725);
DISPLAY 0.638298 (-7165 1725);
PAINT MONO (-7165 1725);
DISPLAY INVISIBLE (-7165 1725);
WIRE 16 -1 (-7075 1675)(-6475 1675);
FORCEPROP 2 LAST SIG_NAME PVDDCR_SOC_P1_LSET2
J 2
(-6535 1685);
DISPLAY 0.489362 (-6535 1685);
FORCEPROP 2 LASTPROP $XRERR UNIQUE?
J 0
(-6775 1685);
DISPLAY 0.638298 (-6775 1685);
PAINT MONO (-6775 1685);
DISPLAY INVISIBLE (-6775 1685);
WIRE 16 -1 (-6475 1475)(-7100 1475);
FORCEPROP 2 LAST SIG_NAME PVDDCR_SOC_P1_TEMP1
J 2
(-6535 1485);
DISPLAY 0.489362 (-6535 1485);
DOT 1 (-4350 2650);
DOT 1 (-1450 2825);
DOT 1 (-875 4750);
DOT 1 (-875 4350);
DOT 1 (-1150 4350);
DOT 1 (-3925 5375);
DOT 1 (-1450 3275);
DOT 1 (-1775 3275);
DOT 1 (-1775 2825);
DOT 1 (-1275 1975);
DOT 1 (-1275 1575);
DOT 1 (-1700 1975);
DOT 1 (-1900 1975);
DOT 1 (-4050 3050);
DOT 1 (-4050 2650);
DOT 1 (-4175 5775);
DOT 1 (-4475 5775);
DOT 1 (-4175 5375);
DOT 1 (-4475 5375);
DOT 1 (-4800 5775);
DOT 1 (-5125 5775);
DOT 1 (-4800 5375);
DOT 1 (-5125 5375);
DOT 1 (-4700 4750);
DOT 1 (-5450 5775);
DOT 1 (-5550 5400);
DOT 1 (-5475 4250);
DOT 1 (-5475 4200);
DOT 1 (-5475 4150);
DOT 1 (-7075 5100);
DOT 1 (-7200 5875);
DOT 1 (-7550 5875);
DOT 1 (-7550 5275);
DOT 1 (-7875 4650);
DOT 1 (-4350 3050);
DOT 1 (-4675 3050);
DOT 1 (-4675 2650);
DOT 1 (-5000 3050);
DOT 1 (-5000 2650);
DOT 1 (-5375 3050);
DOT 1 (-5525 2625);
DOT 1 (-4625 1975);
DOT 1 (-5450 1475);
DOT 1 (-5450 1425);
DOT 1 (-5450 1375);
DOT 1 (-7175 3100);
DOT 1 (-7025 2325);
DOT 1 (-7525 3100);
DOT 1 (-7525 2500);
DOT 1 (-7850 1875);
DOT 1 (-1150 4750);
DOT 1 (-1575 4350);
DOT 1 (-2050 4750);
DOT 1 (-1975 4750);
DOT 1 (-1575 4750);
DOT 1 (-2625 5775);
DOT 1 (-3925 5775);
DOT 1 (-3950 5775);
DOT 1 (-3950 5375);
DOT 1 (-3750 5775);
DOT 1 (-3750 5375);
DOT 1 (-3450 5775);
DOT 1 (-3725 2650);
DOT 1 (-3725 3050);
FORCENOTE
BOM NOTE
(-9625 1250) 0;
DISPLAY LEFT (-9625 1250);
DISPLAY 1.595745 (-9625 1250);
PAINT WHITE (-9625 1250);
FORCENOTE
MAIN SOURCE:RENESAS BOM
(-9625 1150) 0;
DISPLAY LEFT (-9625 1150);
DISPLAY 1.276596 (-9625 1150);
PAINT WHITE (-9625 1150);
FORCENOTE
PU30,PU31,PU32 = AL099390004/ISL99390FRZ-TR5935
(-9625 1075) 0;
DISPLAY LEFT (-9625 1075);
DISPLAY 1.021277 (-9625 1075);
PAINT WHITE (-9625 1075);
FORCENOTE
2ND SOURCE:INFENEON BOM
(-9625 925) 0;
DISPLAY LEFT (-9625 925);
DISPLAY 1.276596 (-9625 925);
PAINT WHITE (-9625 925);
FORCENOTE
PU30,PU31,PU32 = AL087000A03/MP87000GMJTH-C11D-Z
(-9625 325) 0;
DISPLAY LEFT (-9625 325);
DISPLAY 1.021277 (-9625 325);
PAINT WHITE (-9625 325);
FORCENOTE
3RD SOURCE:MPS BOM
(-9625 400) 0;
DISPLAY LEFT (-9625 400);
DISPLAY 1.276596 (-9625 400);
PAINT WHITE (-9625 400);
FORCENOTE
PR207,PR208,PR214 = CS00002JB13
(-9625 700) 0;
DISPLAY LEFT (-9625 700);
DISPLAY 1.021277 (-9625 700);
PAINT WHITE (-9625 700);
FORCENOTE
PR209,PR210,PR215 = CS00002JB13
(-9625 775) 0;
DISPLAY LEFT (-9625 775);
DISPLAY 1.021277 (-9625 775);
PAINT WHITE (-9625 775);
FORCENOTE
PU30,PU31,PU32 = AL021590000/TDA21590
(-9625 850) 0;
DISPLAY LEFT (-9625 850);
DISPLAY 1.021277 (-9625 850);
PAINT WHITE (-9625 850);
FORCENOTE
PR209,PR210,PR215=CS00002JB13
(-9625 250) 0;
DISPLAY LEFT (-9625 250);
DISPLAY 1.021277 (-9625 250);
PAINT WHITE (-9625 250);
FORCENOTE
PC317_7,PC318_8,PC345_9 = EMPTY
(-9625 550) 0;
DISPLAY LEFT (-9625 550);
DISPLAY 1.021277 (-9625 550);
PAINT WHITE (-9625 550);
FORCENOTE
PR211,PR212,PR216 = EMPTY
(-9625 625) 0;
DISPLAY LEFT (-9625 625);
DISPLAY 1.021277 (-9625 625);
PAINT WHITE (-9625 625);
FORCENOTE
PR211,PR212,PR216=EMPTY
(-9625 175) 0;
DISPLAY LEFT (-9625 175);
DISPLAY 1.021277 (-9625 175);
PAINT WHITE (-9625 175);
FORCENOTE
PC317_7,PC318_8,PC345_9=EMPTY
(-9625 100) 0;
DISPLAY LEFT (-9625 100);
DISPLAY 1.021277 (-9625 100);
PAINT WHITE (-9625 100);
FORCENOTE
PVDDCR_SOC_P1_PHASE1
(-6625 6150) 0;
DISPLAY LEFT (-6625 6150);
DISPLAY 1.595745 (-6625 6150);
PAINT WHITE (-6625 6150);
FORCENOTE
ESR=4.5M OHM
(-1950 2750) 0;
DISPLAY LEFT (-1950 2750);
DISPLAY 0.638298 (-1950 2750);
PAINT WHITE (-1950 2750);
FORCENOTE
2ND=CH747LM8822
(-1950 2650) 0;
DISPLAY LEFT (-1950 2650);
DISPLAY 0.638298 (-1950 2650);
PAINT WHITE (-1950 2650);
FORCENOTE
7.3*4.3*1.9
(-1950 2700) 0;
DISPLAY LEFT (-1950 2700);
DISPLAY 0.638298 (-1950 2700);
PAINT WHITE (-1950 2700);
FORCENOTE
DCR=2-3,0.27M OHM
(-2575 2100) 0;
DISPLAY LEFT (-2575 2100);
DISPLAY 0.638298 (-2575 2100);
PAINT WHITE (-2575 2100);
FORCENOTE
DCR=1-4,0.105M OHM
(-2575 2150) 0;
DISPLAY LEFT (-2575 2150);
DISPLAY 0.638298 (-2575 2150);
PAINT WHITE (-2575 2150);
FORCENOTE
PGL6303.151HLT
(-2575 2300) 0;
DISPLAY LEFT (-2575 2300);
DISPLAY 0.638298 (-2575 2300);
PAINT WHITE (-2575 2300);
FORCENOTE
ISAT:70A@100C
(-2575 2250) 0;
DISPLAY LEFT (-2575 2250);
DISPLAY 0.638298 (-2575 2250);
PAINT WHITE (-2575 2250);
FORCENOTE
11.0*7.5*12.5
(-2575 2200) 0;
DISPLAY LEFT (-2575 2200);
DISPLAY 0.638298 (-2575 2200);
PAINT WHITE (-2575 2200);
FORCENOTE
2ND=CV+15^0TZ01
(-2575 2050) 0;
DISPLAY LEFT (-2575 2050);
DISPLAY 0.638298 (-2575 2050);
PAINT WHITE (-2575 2050);
FORCENOTE
DCR=2-3,0.27M OHM
(-2825 4850) 0;
DISPLAY LEFT (-2825 4850);
DISPLAY 0.638298 (-2825 4850);
PAINT WHITE (-2825 4850);
FORCENOTE
2ND=CV+15^0TZ01
(-2825 4800) 0;
DISPLAY LEFT (-2825 4800);
DISPLAY 0.638298 (-2825 4800);
PAINT WHITE (-2825 4800);
FORCENOTE
DCR=1-4,0.105M OHM
(-2825 4900) 0;
DISPLAY LEFT (-2825 4900);
DISPLAY 0.638298 (-2825 4900);
PAINT WHITE (-2825 4900);
FORCENOTE
11.0*7.5*12.5
(-2825 4950) 0;
DISPLAY LEFT (-2825 4950);
DISPLAY 0.638298 (-2825 4950);
PAINT WHITE (-2825 4950);
FORCENOTE
ISAT:70A@100C
(-2825 5000) 0;
DISPLAY LEFT (-2825 5000);
DISPLAY 0.638298 (-2825 5000);
PAINT WHITE (-2825 5000);
FORCENOTE
ESR=10M OHM
(-3750 5325) 0;
DISPLAY LEFT (-3750 5325);
DISPLAY 0.638298 (-3750 5325);
PAINT WHITE (-3750 5325);
FORCENOTE
3RD=CVA50^0MZ08
(-3225 5450) 0;
DISPLAY LEFT (-3225 5450);
DISPLAY 0.638298 (-3225 5450);
PAINT WHITE (-3225 5450);
FORCENOTE
PGL6303.151HLT
(-2825 5050) 0;
DISPLAY LEFT (-2825 5050);
DISPLAY 0.638298 (-2825 5050);
PAINT WHITE (-2825 5050);
FORCENOTE
PG2292.500HLT
(-3225 5700) 0;
DISPLAY LEFT (-3225 5700);
DISPLAY 0.638298 (-3225 5700);
PAINT WHITE (-3225 5700);
FORCENOTE
6.0*6.1*7.0
(-3225 5600) 0;
DISPLAY LEFT (-3225 5600);
DISPLAY 0.638298 (-3225 5600);
PAINT WHITE (-3225 5600);
FORCENOTE
ISAT:70A@100C
(-3225 5650) 0;
DISPLAY LEFT (-3225 5650);
DISPLAY 0.638298 (-3225 5650);
PAINT WHITE (-3225 5650);
FORCENOTE
DCR=0.09M OHM
(-3225 5550) 0;
DISPLAY LEFT (-3225 5550);
DISPLAY 0.638298 (-3225 5550);
PAINT WHITE (-3225 5550);
FORCENOTE
2ND=CVA50^0MZ07
(-3225 5500) 0;
DISPLAY LEFT (-3225 5500);
DISPLAY 0.638298 (-3225 5500);
PAINT WHITE (-3225 5500);
FORCENOTE
2ND=CC72703MD39
(-3750 5175) 0;
DISPLAY LEFT (-3750 5175);
DISPLAY 0.638298 (-3750 5175);
PAINT WHITE (-3750 5175);
FORCENOTE
6.3*8
(-3750 5225) 0;
DISPLAY LEFT (-3750 5225);
DISPLAY 0.638298 (-3750 5225);
PAINT WHITE (-3750 5225);
FORCENOTE
IRIPPLE:5.08A
(-3750 5275) 0;
DISPLAY LEFT (-3750 5275);
DISPLAY 0.638298 (-3750 5275);
PAINT WHITE (-3750 5275);
FORCENOTE
PVDDCR_SOC_P1_PHASE2
(-6600 3375) 0;
DISPLAY LEFT (-6600 3375);
DISPLAY 1.595745 (-6600 3375);
PAINT WHITE (-6600 3375);
QUIT
